# Lightning_PEB_EQL.xlsx — PEBlength (si-constraints)
| 15105-1.1115WPH1358.brd |  |  |  |
| Date Tue Nov 15 15:44:49 2016 |  |  |  |
| Net Name | Etch Length (mils) | Manhattan Length (mils) | Percent Manhattan (mils) |
| 50M_CLK_OE | 101.18 | 105.77 | 95.66 |
| 50M_CLK_OUT | 91.38 | 94.13 | 97.08 |
| 50M_CLK_OUT_R | 85.11 | 94.23 | 90.32 |
| 8644_CBL_PRSNT_R_1 | 605.54 | 563.52 | 107.46 |
| 8644_CBL_PRSNT_R_2 | 655.99 | 630.84 | 103.99 |
| 8644_CBL_PRSNT_R_3 | 638.53 | 615.72 | 103.7 |
| 8644_CBL_PRSNT_R_4 | 601.01 | 575.23 | 104.48 |
| 8644_CBL_PRSNT_R_5 | 652.48 | 815.81 | 79.98 |
| 8644_CBL_PRSNT_R_6 | 1807.29 | 1387.15 | 130.29 |
| 8644_CBL_PRSNT_R_7 | 2431.81 | 2190.23 | 111.03 |
| 8644_CBL_PRSNT_R_8 | 2411.87 | 2534.89 | 95.15 |
| 8644_SDA_R_1 | 780.48 | 793.12 | 98.41 |
| 8644_SDA_R_2 | 821.09 | 700.54 | 117.21 |
| 8644_SDA_R_3 | 773.1 | 719.02 | 107.52 |
| 8644_SDA_R_4 | 750.1 | 769.83 | 97.44 |
| 8644_SDA_R_5 | 790.71 | 823.3 | 96.04 |
| 8644_SDA_R_6 | 1410.42 | 1387.96 | 101.62 |
| 8644_SDA_R_7 | 1673.3 | 1891.22 | 88.48 |
| 8644_SDA_R_8 | 2469.79 | 2515.29 | 98.19 |
| 8644_USB_DN1 | 502.76 | 547.79999999999995 | 91.78 |
| 8644_USB_DN2 | 376.42 | 320.23 | 117.55 |
| 8644_USB_DN3 | 381.09 | 330.49 | 115.31 |
| 8644_USB_DN4 | 974.64 | 955.72 | 101.98 |
| 8644_USB_DN5 | 800.08 | 925.5 | 86.45 |
| 8644_USB_DN6 | 373.31 | 307.54000000000002 | 121.39 |
| 8644_USB_DN7 | 372.52 | 307.2 | 121.26 |
| 8644_USB_DN8 | 414.06 | 400.09 | 103.49 |
| 8644_USB_DP1 | 503.64 | 592.46 | 85.01 |
| 8644_USB_DP2 | 377.55 | 364.78 | 103.5 |
| 8644_USB_DP3 | 383.82 | 396.11 | 96.9 |
| 8644_USB_DP4 | 975.44 | 935.02 | 104.32 |
| 8644_USB_DP5 | 799.51 | 940.01 | 85.05 |
| 8644_USB_DP6 | 372.78 | 366.14 | 101.81 |
| 8644_USB_DP7 | 371.7 | 365.24 | 101.77 |
| 8644_USB_DP8 | 413.36 | 465.76 | 88.75 |
| ADC0_12V_BMC | 931.16 | 811.14 | 114.8 |
| ADCAV33 | 787.91 | 665.03 | 118.48 |
| ADCVREFFN | 368.32 | 383.14 | 96.13 |
| ADCVREFFP | 309.29000000000002 | 316.64 | 97.68 |
| ADCVREXT | 141.69 | 59.04 | 239.99 |
| ADC_12V | 216.25 | 155 | 139.51 |
| ADC_P0V9 | 186.16 | 150 | 124.11 |
| ADC_P0V9_BMC | 905.45 | 824.64 | 109.8 |
| ADC_P0V9_E | 195.57 | 120 | 162.97999999999999 |
| ADC_P0V9_E_BMC | 461.88 | 553.14 | 83.5 |
| ADC_P1V26 | 1146.1099999999999 | 1146 | 100.01 |
| ADC_P1V26_BMC | 405.61 | 481.64 | 84.21 |
| ADC_P1V53V | 174.16 | 161 | 108.17 |
| ADC_P1V53_BMC | 305.35000000000002 | 360.15 | 84.78 |
| ADC_P1V8_STBY | 205.59 | 160 | 128.5 |
| ADC_P1V8_STBY_BMC | 354.5 | 431.65 | 82.13 |
| ADC_P3V3_STBY | 211.08 | 160 | 131.93 |
| ADC_P3V3_STBY_BMC | 381.38 | 423.14 | 90.13 |
| ADC_P5V_STBY | 162.93 | 160 | 101.83 |
| ADC_P5V_STBY_BMC | 429.52 | 494.64 | 86.84 |
| ADM1278_HS_N | 162.25 | 189.47 | 85.63 |
| ADM1278_HS_P | 155.91 | 174.16 | 89.52 |
| ADM6315_PM8536_RST# | 396.23 | 330.47 | 119.9 |
| AGND_CURRENT_MON | 1173.03 | 2341.5 | 50.1 |
| AGND_P0V9 | 568.66 | 487.76 | 116.59 |
| AGND_P0V9_E | 850.87 | 701.5 | 121.29 |
| AGND_P3V3_STBY | 868.16 | 808.9 | 107.33 |
| AGND_USB | 540.16 | 887.12 | 60.89 |
| AS_ROMA0_R | 166.85 | 172.5 | 96.72 |
| AVS_ENB | 11319.89 | 10052.450000000001 | 112.61 |
| AVS_ENB1_R | 173.79 | 192.66 | 90.21 |
| AVS_ENB2_R | 182.73 | 112.5 | 162.41999999999999 |
| AVS_ENB_R | 403.35 | 413.31 | 97.59 |
| BMC0_ENTEST1 | 208.84 | 171.43 | 121.82 |
| BMC0_JTAG_RTCK | 1294.83 | 1024.06 | 126.44 |
| BMC0_LED_DR_R_LED0 | 348.92 | 463.69 | 75.25 |
| BMC0_SCL11_R | 1016.95 | 1072.21 | 94.85 |
| BMC0_SCL12_R | 596.67999999999995 | 692.07 | 86.22 |
| BMC0_SCL13_R | 500.28 | 638.09 | 78.400000000000006 |
| BMC0_SDA11_R | 1166.58 | 1252.07 | 93.17 |
| BMC0_SDA12_R | 566.22 | 669.07 | 84.63 |
| BMC0_SDA13_R | 428.8 | 534.09 | 80.290000000000006 |
| BMC0_SMB10_CLK | 470.31 | 529.22 | 88.87 |
| BMC0_SMB10_DAT | 450.14 | 506.23 | 88.92 |
| BMC0_SMB14_CLK | 328 | 316.13 | 103.75 |
| BMC0_SMB14_SDA | 290.95 | 244.63 | 118.93 |
| BMC0_SMB1_CLK | 832.05 | 940.44 | 88.47 |
| BMC0_SMB1_DAT | 797.41 | 949.94 | 83.94 |
| BMC0_SMB2_CLK | 561.62 | 600.9 | 93.46 |
| BMC0_SMB2_DAT | 574.63 | 592.4 | 97 |
| BMC0_SMB3_CLK | 634.04 | 737.95 | 85.92 |
| BMC0_SMB3_DAT | 544.01 | 634.96 | 85.68 |
| BMC0_SMB4_CLK | 1087 | 850.97 | 127.74 |
| BMC0_SMB4_DAT | 1265.32 | 1062.94 | 119.04 |
| BMC0_SMB5_CLK | 420.62 | 475.9 | 88.38 |
| BMC0_SMB5_DAT | 393.79 | 452.91 | 86.95 |
| BMC0_SMB6_CLK | 1087.99 | 711.08 | 153 |
| BMC0_SMB6_DAT | 1166.21 | 860.06 | 135.6 |
| BMC0_SMB7_CLK | 443.83 | 540.58000000000004 | 82.1 |
| BMC0_SMB7_DAT | 413.95 | 517.58000000000004 | 79.98 |
| BMC0_SMB8_CLK | 474.36 | 523.25 | 90.66 |
| BMC0_SMB8_DAT | 406.53 | 468.75 | 86.73 |
| BMC0_SMB9_CLK | 447.85 | 475.35 | 94.22 |
| BMC0_SMB9_DAT | 441.47 | 452.36 | 97.59 |
| BMC0_SRST_N | 517.24 | 603.33000000000004 | 85.73 |
| BMC0_TACH13 | 724.47 | 765.66 | 94.62 |
| BMC_ADD1 | 5238.68 | 6026.91 | 86.92 |
| BMC_ADD2 | 7757.37 | 5955.55 | 130.25 |
| BMC_ADD1_GND | 157.5 | 171.49 | 91.84 |
| BMC_ADD1_PWR | 104.3 | 111.27 | 93.74 |
| BMC_ADD1_R | 562.63 | 564.03 | 99.75 |
| BMC_ADD2_GND | 110.9 | 121.95 | 90.94 |
| BMC_ADD2_PWR | 128.47 | 140.71 | 91.3 |
| BMC_ADD2_R | 352.44 | 339.93 | 103.68 |
| BMC_CONSOLE_LED0_R | 123.05 | 71.25 | 172.71 |
| BMC_CPU_DIS | 156.32 | 169.5 | 92.22 |
| BMC_CPU_EN | 122.91 | 135.5 | 90.71 |
| BMC_DDR3_RST_N | 1304.8800000000001 | 1047.78 | 124.54 |
| BMC_ENCLOSURE_LED | 11503.41 | 11073.49 | 103.88 |
| BMC_ENCLOSURE_LED_R | 117.13 | 105 | 111.55 |
| BMC_FW_DET_BOARD_VER_0 | 489.45 | 469.67 | 104.21 |
| BMC_FW_DET_BOARD_VER_1 | 485.07 | 518.17999999999995 | 93.61 |
| BMC_FW_DET_BOARD_VER_2 | 406.09 | 415.19 | 97.81 |
| BMC_I210_PERST_N | 3099.78 | 3332.16 | 93.03 |
| BMC_I2C10_8536_SCL | 4041.61 | 3780.35 | 106.91 |
| BMC_I2C10_8536_SCL_R | 252.61 | 196.2 | 128.75 |
| BMC_I2C10_8536_SDA | 3976.56 | 3695.35 | 107.61 |
| BMC_I2C10_8536_SDA_R | 259.12 | 201.2 | 128.79 |
| BMC_I2C11_MINI5_SCL | 12629.54 | 12195.89 | 103.56 |
| BMC_I2C11_MINI5_SCL_S | 8817.5 | 8816.32 | 100.01 |
| BMC_I2C11_MINI5_SDA | 12252.83 | 12354.79 | 99.17 |
| BMC_I2C11_MINI5_SDA_S | 8543.9599999999991 | 8880.94 | 96.21 |
| BMC_I2C12_MINI6_SCL | 13843.19 | 13091.03 | 105.75 |
| BMC_I2C12_MINI6_SCL_S | 537.53 | 311.17 | 172.74 |
| BMC_I2C12_MINI6_SDA | 12731.53 | 12972.67 | 98.14 |
| BMC_I2C12_MINI6_SDA_S | 250.98 | 186.83 | 134.34 |
| BMC_I2C13_MINI7_SCL | 14260.48 | 13517.11 | 105.5 |
| BMC_I2C13_MINI7_SCL_S | 486.14 | 281.93 | 172.43 |
| BMC_I2C13_MINI7_SDA | 12393.88 | 13109.07 | 94.54 |
| BMC_I2C13_MINI7_SDA_S | 210.86 | 158.83000000000001 | 132.76 |
| BMC_I2C14_MINI8_SCL | 14442.87 | 14059.21 | 102.73 |
| BMC_I2C14_MINI8_SCL_S | 8179.39 | 5085 | 160.85 |
| BMC_I2C14_MINI8_SDA | 11939.17 | 12885.9 | 92.65 |
| BMC_I2C14_MINI8_SDA_S | 8388.8700000000008 | 4803 | 174.66 |
| BMC_I2C1_MINI1_SCL | 7991.15 | 8715.27 | 91.69 |
| BMC_I2C1_MINI1_SCL_S | 8840.06 | 7801.67 | 113.31 |
| BMC_I2C1_MINI1_SDA | 7759.28 | 8366.5 | 92.74 |
| BMC_I2C1_MINI1_SDA_S | 9034.35 | 7817.44 | 115.57 |
| BMC_I2C2_MINI2_SCL | 8694.15 | 9342.44 | 93.06 |
| BMC_I2C2_MINI2_SCL_S | 498.62 | 422.13 | 118.12 |
| BMC_I2C2_MINI2_SDA | 8128.35 | 8793.27 | 92.44 |
| BMC_I2C2_MINI2_SDA_S | 361.34 | 233.41 | 154.81 |
| BMC_I2C3_MINI3_SCL | 7302.64 | 7483.42 | 97.58 |
| BMC_I2C3_MINI3_SCL_S | 476.38 | 290.88 | 163.77000000000001 |
| BMC_I2C3_MINI3_SDA | 6867.93 | 7137.04 | 96.23 |
| BMC_I2C3_MINI3_SDA_S | 199.2 | 166.52 | 119.62 |
| BMC_I2C4_MINI4_SCL | 7511.13 | 7921.59 | 94.82 |
| BMC_I2C4_MINI4_SCL_S | 320.19 | 286.89999999999998 | 111.6 |
| BMC_I2C4_MINI4_SDA | 7109.21 | 7305.9 | 97.31 |
| BMC_I2C4_MINI4_SDA_S | 673.59 | 388 | 173.6 |
| BMC_I2C5_BUF_READY | 145.09 | 89.4 | 162.29 |
| BMC_I2C5_D_PEB_DEVICE_SCL | 7710.14 | 6984.35 | 110.39 |
| BMC_I2C5_D_PEB_DEVICE_SDA | 7777.64 | 7238.35 | 107.45 |
| BMC_I2C5_D_PEB_SCL | 22749.31 | 16874.37 | 134.82 |
| BMC_I2C5_D_PEB_SDA | 22662.9 | 17040.91 | 132.99 |
| BMC_I2C5_SCL_R | 304.82 | 241.2 | 126.38 |
| BMC_I2C5_SDA_R | 292.58 | 246.2 | 118.84 |
| BMC_I2C6_C_FCB_SCL | 3871.43 | 3915 | 98.89 |
| BMC_I2C6_C_FCB_SCL_R | 260.12 | 196.2 | 132.58000000000001 |
| BMC_I2C6_C_FCB_SDA | 3910.67 | 3915 | 99.89 |
| BMC_I2C6_C_FCB_SDA_R | 254.35 | 201.2 | 126.41 |
| BMC_I2C7_B_DBP_SCL | 3295.01 | 3155 | 104.44 |
| BMC_I2C7_B_DBP_SCL_R | 252.8 | 196.2 | 128.85 |
| BMC_I2C7_B_DPB_SDA | 3344.37 | 3235 | 103.38 |
| BMC_I2C7_B_DPB_SDA_R | 253.98 | 201.2 | 126.23 |
| BMC_I2C8_CLKBUF1_SCL | 12399.85 | 12294.5 | 100.86 |
| BMC_I2C8_CLKBUF1_SCL_R | 252.91 | 196.2 | 128.9 |
| BMC_I2C8_CLKBUF1_SDA | 12378.53 | 12293.5 | 100.69 |
| BMC_I2C8_CLKBUF1_SDA_R | 250.93 | 201.2 | 124.72 |
| BMC_I2C9_CLKBUF2_SCL | 3282.05 | 3073 | 106.8 |
| BMC_I2C9_CLKBUF2_SCL_R | 253 | 196.2 | 128.94999999999999 |
| BMC_I2C9_CLKBUF2_SDA | 3343.49 | 3155 | 105.97 |
| BMC_I2C9_CLKBUF2_SDA_R | 251.72 | 201.2 | 125.11 |
| BMC_ID_LED | 10904.72 | 11024.75 | 98.91 |
| BMC_ID_LED_R | 131.34 | 133.28 | 98.54 |
| BMC_INT_N | 6298.9 | 6101.42 | 103.24 |
| BMC_JTAG_L_EN | 164.01 | 134.30000000000001 | 122.12 |
| BMC_JTAG_L_EN_R | 306.98 | 353.64 | 86.81 |
| BMC_MIOZ | 726.74 | 659.04 | 110.27 |
| BMC_PEREXT | 351.32 | 441.95 | 79.489999999999995 |
| BMC_PERST#15 | 207.88 | 123.1 | 168.87 |
| BMC_PERST#_R | 19215.419999999998 | 16581.759999999998 | 115.88 |
| BMC_PETXN | 10042.32 | 10270 | 97.78 |
| BMC_PETXP | 10042.52 | 10266.5 | 97.82 |
| BMC_REFCLK_N | 1364.94 | 1051.31 | 129.83000000000001 |
| BMC_REFCLK_P | 1365.82 | 981.01 | 139.22999999999999 |
| BMC_RESET#_DDR3 | 237.52 | 180 | 131.96 |
| BMC_RESET#_DDR3_BUF | 105.94 | 54.4 | 194.74 |
| BMC_RXCK_R | 709.5 | 718.55 | 98.74 |
| BMC_RXD5 | 13139.4 | 12713.12 | 103.35 |
| BMC_RXD5_R | 1718.4 | 1397.31 | 122.98 |
| BMC_R_RXD5 | 149.80000000000001 | 150.44 | 99.57 |
| BMC_R_TXD5 | 151.97 | 152.94 | 99.37 |
| BMC_SELF_HW_RST | 2549.48 | 2044.67 | 124.69 |
| BMC_SELF_HW_RST_R | 407.25 | 458.56 | 88.81 |
| BMC_SELF_TRAY | 3992.28 | 4089.2 | 97.63 |
| BMC_SELF_TRAY_R | 686.52 | 654.16999999999996 | 104.95 |
| BMC_SSD_RST#0 | 4597.84 | 3325.77 | 138.25 |
| BMC_SSD_RST#1 | 5170.88 | 5912.77 | 87.45 |
| BMC_SSD_RST#2 | 5761.8 | 6245.26 | 92.26 |
| BMC_SSD_RST#3 | 8874.73 | 9312.77 | 95.3 |
| BMC_SSD_RST#4 | 13823.23 | 12883.18 | 107.3 |
| BMC_SSD_RST#5 | 4625.3599999999997 | 3406.28 | 135.79 |
| BMC_SSD_RST#6 | 5944.22 | 6421.76 | 92.56 |
| BMC_SSD_RST#7 | 7632.93 | 6741.05 | 113.23 |
| BMC_SSD_RST#8 | 11713.01 | 10571.54 | 110.8 |
| BMC_SSD_RST#9 | 17134.14 | 14396.54 | 119.02 |
| BMC_SSD_RST#10 | 7456.41 | 4590.6499999999996 | 162.43 |
| BMC_SSD_RST#11 | 6875.58 | 4054.04 | 169.6 |
| BMC_SSD_RST#12 | 11918.28 | 10743.13 | 110.94 |
| BMC_SSD_RST#13 | 11005.4 | 9826.56 | 112 |
| BMC_SSD_RST#14 | 17335.990000000002 | 14389.06 | 120.48 |
| BMC_SSD_RST#0_A0 | 168.07 | 156.33000000000001 | 107.51 |
| BMC_SSD_RST#0_A1 | 165.14 | 156.33000000000001 | 105.63 |
| BMC_SSD_RST#0_A2 | 179.03 | 156.09 | 114.7 |
| BMC_SSD_RST#0_A3 | 156.46 | 181 | 86.44 |
| BMC_SSD_RST#0_A4 | 147.71 | 101.93 | 144.91 |
| BMC_SSD_RST#0_A5 | 186.96 | 151.09 | 123.74 |
| BMC_SSD_RST#0_A6 | 186.15 | 156.33000000000001 | 119.08 |
| BMC_SSD_RST#0_A7 | 184.53 | 135.93 | 135.75 |
| BMC_SSD_RST#0_A8 | 170.03 | 202.6 | 83.92 |
| BMC_SSD_RST#0_A9 | 165.16 | 153.62 | 107.51 |
| BMC_SSD_RST#0_A10 | 179.89 | 146.33000000000001 | 122.93 |
| BMC_SSD_RST#0_A11 | 159.38 | 126.93 | 125.56 |
| BMC_SSD_RST#0_A12 | 172.57 | 133.02000000000001 | 129.72999999999999 |
| BMC_SSD_RST#0_A13 | 195.96 | 106.31 | 184.33 |
| BMC_SSD_RST#0_A14 | 194.19 | 153.24 | 126.72 |
| BMC_TPM_RST | 255.29 | 283.99 | 89.89 |
| BMC_TXD5 | 14484.06 | 12906.1 | 112.23 |
| BMC_TXD5_R | 1397.97 | 1288.45 | 108.5 |
| BMC_UART_SWITCH_1 | 11927.25 | 12275.49 | 97.16 |
| BMC_USB1_HDN | 309.63 | 299.64 | 103.33 |
| BMC_USB1_HDN2 | 307.14999999999998 | 302.63 | 101.49 |
| BMC_USB1_HDP | 309.77 | 305.06 | 101.55 |
| BMC_USB1_HDP2 | 307.83999999999997 | 294.13 | 104.66 |
| BMC_USB2_HDN | 246.33 | 312.06 | 78.94 |
| BMC_USB2_HDP | 245.4 | 240.57 | 102.01 |
| BMC_USB_EN_1 | 2480.27 | 2435.06 | 101.86 |
| BOOTSTRAP0 | 194.38 | 75 | 259.17 |
| BOOTSTRAP1 | 159.47999999999999 | 75 | 212.65 |
| BOOTSTRAP2 | 169.15 | 75 | 225.53 |
| BOOTSTRAP3 | 172.39 | 75 | 229.85 |
| BOOTSTRAP4 | 189.56 | 75 | 252.74 |
| BOOTSTRAP5 | 195.89 | 75 | 261.18 |
| BOOTSTRAP6 | 151.27000000000001 | 75 | 201.69 |
| BOOTSTRAP7 | 219.75 | 75 | 293 |
| BOOTSTRAP8 | 170.8 | 75 | 227.74 |
| BOOTSTRAP9 | 190.67 | 75 | 254.23 |
| BOOTSTRAP10 | 171.46 | 75 | 228.62 |
| BOOTSTRAP_R_0 | 446.14 | 414.9 | 107.53 |
| BOOTSTRAP_R_1 | 346.99 | 374.78 | 92.59 |
| BOOTSTRAP_R_2 | 486.07 | 459.15 | 105.86 |
| BOOTSTRAP_R_3 | 249.61 | 251.04 | 99.43 |
| BOOTSTRAP_R_4 | 470.44 | 554.78 | 84.8 |
| BOOTSTRAP_R_5 | 318.02999999999997 | 330.53 | 96.22 |
| BOOTSTRAP_R_6 | 743.71 | 824.74 | 90.17 |
| BOOTSTRAP_R_7 | 578.30999999999995 | 622.26 | 92.94 |
| BOOTSTRAP_R_8 | 785.8 | 836 | 93.99 |
| BOOTSTRAP_R_9 | 920.97 | 920.37 | 100.06 |
| BOOTSTRAP_R_10 | 887.26 | 926 | 95.82 |
| BOOT_RECOVERY# | 1917.87 | 2182.66 | 87.87 |
| BOOT_RECOVERY#_R | 111.79 | 125.03 | 89.41 |
| BOOT_RECOVERY_0 | 124.42 | 162.5 | 76.569999999999993 |
| BOOT_RECOVERY_1 | 120.43 | 146.5 | 82.21 |
| BP_PRSNT_N | 6461.19 | 6053.74 | 106.73 |
| BUF_I2C5_SCL_R | 257.13 | 196.2 | 131.05000000000001 |
| BUF_I2C5_SDA_R | 255.02 | 201.2 | 126.75 |
| BUF_I2C6_C_FCB_SCL | 1030.19 | 1014.2 | 101.58 |
| BUF_I2C6_C_FCB_SCL_R | 278.24 | 241.2 | 115.36 |
| BUF_I2C6_C_FCB_SDA | 1026.99 | 995.7 | 103.14 |
| BUF_I2C6_C_FCB_SDA_R | 277.77999999999997 | 246.2 | 112.83 |
| BUF_I2C7_B_DBP_SCL | 1379.72 | 1455.23 | 94.81 |
| BUF_I2C7_B_DBP_SCL_R | 282.32 | 241.2 | 117.05 |
| BUF_I2C7_B_DPB_SDA | 1377.06 | 1436.72 | 95.85 |
| BUF_I2C7_B_DPB_SDA_R | 286.83999999999997 | 246.2 | 116.51 |
| BUF_I2C8_CLKBUF1_SCL | 2187.0700000000002 | 1962.24 | 111.46 |
| BUF_I2C8_CLKBUF1_SCL_R | 276.10000000000002 | 241.2 | 114.47 |
| BUF_I2C8_CLKBUF1_SDA | 2183.67 | 1943.73 | 112.34 |
| BUF_I2C8_CLKBUF1_SDA_R | 280.7 | 246.2 | 114.01 |
| BUF_I2C9_CLKBUF2_SCL | 1674.5 | 1547.72 | 108.19 |
| BUF_I2C9_CLKBUF2_SCL_R | 283.45999999999998 | 241.2 | 117.52 |
| BUF_I2C9_CLKBUF2_SDA | 1669.93 | 1531.21 | 109.06 |
| BUF_I2C9_CLKBUF2_SDA_R | 284.89 | 246.2 | 115.71 |
| BUF_I2C_SCL_2_R | 274.44 | 241.2 | 113.78 |
| BUF_I2C_SDA_2_R | 279.86 | 246.2 | 113.67 |
| BUS_SW_OE# | 170.1 | 133.29 | 127.62 |
| CBL_PRSNT_N_1 | 7537.17 | 7468.67 | 100.92 |
| CBL_PRSNT_N_2 | 8037.16 | 8273.0300000000007 | 97.15 |
| CBL_PRSNT_N_3 | 8489.3799999999992 | 8672.2000000000007 | 97.89 |
| CBL_PRSNT_N_4 | 8304.41 | 8889.68 | 93.42 |
| CBL_PRSNT_N_5 | 13648.62 | 14373.45 | 94.96 |
| CBL_PRSNT_N_6 | 13597.44 | 14277.78 | 95.23 |
| CBL_PRSNT_N_7 | 13547.62 | 14673.18 | 92.33 |
| CBL_PRSNT_N_8 | 14192.29 | 15023.18 | 94.47 |
| CLKGEN_N2 | 48.49 | 47.5 | 102.09 |
| CLKGEN_N3 | 50.4 | 54.5 | 92.48 |
| CLKGEN_N1_R | 108 | 105.04 | 102.82 |
| CLKGEN_N2_R | 126.21 | 150.36000000000001 | 83.94 |
| CLKGEN_N3_R | 112.45 | 117.73 | 95.51 |
| CLKGEN_OE1 | 128.5 | 128.5 | 100 |
| CLKGEN_OE2 | 133.11000000000001 | 132.5 | 100.46 |
| CLKGEN_OE3 | 137.5 | 137.5 | 100 |
| CLKGEN_OE1_R | 186.46 | 143.66999999999999 | 129.78 |
| CLKGEN_OE2_R | 145.82 | 178.67 | 81.62 |
| CLKGEN_OE3_R | 99.47 | 94.73 | 105.01 |
| CLKGEN_P2 | 48.33 | 49.5 | 97.63 |
| CLKGEN_P3 | 53.71 | 62.5 | 85.94 |
| CLKGEN_P1_R | 108.04 | 125.36 | 86.19 |
| CLKGEN_P2_R | 126.44 | 120.04 | 105.33 |
| CLKGEN_P3_R | 112.98 | 140.04 | 80.680000000000007 |
| CLKGEN_PWGD | 314.94 | 255.36 | 123.33 |
| CLKGEN_SCL | 167.76 | 135.36000000000001 | 123.94 |
| CLKGEN_SDA | 126.78 | 115.04 | 110.2 |
| CLKGNE_SADR | 170.13 | 202.04 | 84.21 |
| CLKGNE_SADR_R | 153.91 | 172.3 | 89.32 |
| CLKGNE_SS_EN | 304.63 | 293.67 | 103.73 |
| CLK_50M_BMC0 | 1240.02 | 1353.14 | 91.64 |
| CLK_50M_BMC_NCSI | 2919.33 | 2175.77 | 134.16999999999999 |
| CLK_50M_BMC_NCSI_R | 295.32 | 318.05 | 92.85 |
| CLK_50M_RMII_PHY | 1648.23 | 1369.16 | 120.38 |
| CLK_50M_RMII_PHY_IN | 120.14 | 101.63 | 118.22 |
| CLK_N_2 | 931.84 | 1004 | 92.81 |
| CLK_N_4 | 654 | 588 | 111.22 |
| CLK_N_6 | 1076.93 | 1179.52 | 91.3 |
| CLK_N_8 | 892.16 | 861.82 | 103.52 |
| CLK_P_2 | 933.04 | 878.22 | 106.24 |
| CLK_P_4 | 651.08000000000004 | 603.04 | 107.97 |
| CLK_P_6 | 1072.53 | 1159.6099999999999 | 92.49 |
| CLK_P_8 | 893.41 | 817.58 | 109.27 |
| CLK_P_1_R | 97.03 | 119.7 | 81.06 |
| CLK_P_2_R | 43.3 | 47.44 | 91.26 |
| CLK_P_3_R | 134.38 | 141.97999999999999 | 94.65 |
| CLK_P_4_R | 97.33 | 120.7 | 80.64 |
| CLK_P_5_R | 474.02 | 161.49 | 293.52999999999997 |
| CLK_P_6_R | 120.18 | 125.43 | 95.82 |
| CLK_P_7_R | 197.08 | 114.21 | 172.56 |
| CLK_P_8_R | 141.41 | 173.49 | 81.510000000000005 |
| CN2_P23 | 255.55 | 209.8 | 121.81 |
| CONSOLE_LED_0 | 67.47 | 74.5 | 90.56 |
| DACB | 91.89 | 78.86 | 116.52 |
| DACG | 64.209999999999994 | 52.54 | 122.21 |
| DACR | 187.82 | 198.04 | 94.84 |
| DACRSET | 270.87 | 301.66000000000003 | 89.79 |
| DDR_VREF | 3120.85 | 1537.86 | 202.93 |
| DEBUG_CARD_RX | 412.53 | 455.54 | 90.56 |
| DEBUG_CARD_TX | 880.98 | 455.54 | 193.39 |
| DEBUG_CONSOLE_LED_0 | 108.14 | 134.5 | 80.400000000000006 |
| DIVIDER_1_IN | 466.9 | 478.61 | 97.55 |
| DIVIDER_2_IN | 163.66999999999999 | 176.83 | 92.56 |
| DPB_HW_REVISION | 7121.02 | 4893.6899999999996 | 145.51 |
| DP_BMC_CPU_RST_N_R | 310.23 | 381.59 | 81.3 |
| DP_RST_N | 15128.76 | 15140.92 | 99.92 |
| DP_RST_N_R | 375.6 | 435.57 | 86.23 |
| DUT_AVD_PCIE | 5659.22 | 9881.32 | 57.27 |
| DUT_AVD_PCIE_Q | 254.43 | 4037.56 | 6.3 |
| DUT_AVD_TX | 4745.5 | 6578.91 | 72.13 |
| DUT_TAP_SEL | 92.15 | 93.2 | 98.87 |
| DUT_TAP_SEL_R | 1066.8900000000001 | 1169.67 | 91.21 |
| DUT_TDI | 55.5 | 76 | 73.02 |
| DUT_TDI_R | 5821.96 | 3894 | 149.51 |
| DUT_TDO | 98.68 | 98.59 | 100.09 |
| DUT_TDO_R | 6455.94 | 4059.63 | 159.03 |
| DUT_VDD | 7496.63 | 11426.35 | 65.61 |
| DUT_VDDO | 11765.66 | 17759.560000000001 | 66.25 |
| DUT_VDDO_REF | 244.68 | 1897.81 | 12.89 |
| EEPROM_A0 | 153.59 | 160.16 | 95.9 |
| EEPROM_A1 | 142.4 | 147.5 | 96.54 |
| EEPROM_A2 | 154.07 | 177.5 | 86.8 |
| EEPROM_A0_R | 194.39 | 110.97 | 175.17 |
| EEPROM_A1_R | 191.68 | 109.27 | 175.42 |
| EEPROM_A2_R | 197.43 | 112.74 | 175.12 |
| EEPROM_SCL | 154.83000000000001 | 5.97 | 2593.4899999999998 |
| EEPROM_SDA | 153.44999999999999 | 4.2699999999999996 | 3593.78 |
| EEPROM_WP | 120.84 | 95.02 | 127.17 |
| EEPROM_WP_8536 | 145.78 | 137.5 | 106.02 |
| EJTAG_DINT | 159.65 | 170.62 | 93.57 |
| EJTAG_PWR | 202.04 | 104.62 | 193.12 |
| EJTAG_RSTB | 7186.62 | 3801.28 | 189.06 |
| EJTAG_TCK | 207.74 | 243.1 | 85.46 |
| EJTAG_TCK_R | 7569.4 | 3567.52 | 212.18 |
| EJTAG_TDI | 153.11000000000001 | 174.21 | 87.89 |
| EJTAG_TDO | 136.32 | 162.47 | 83.91 |
| EJTAG_TMS | 251.04 | 191.84 | 130.86000000000001 |
| EJTAG_TMS_R | 6926.6 | 3653.18 | 189.6 |
| EJTAG_TRSTB | 227.83 | 280.94 | 81.099999999999994 |
| EJTAG_TRSTB_R | 6739.17 | 4338.55 | 155.33000000000001 |
| ENCLO_LED_BLUE_OUT | 122.06 | 86.15 | 141.69 |
| ENCLO_LED_RED | 684.05 | 802.1 | 85.28 |
| ENCLO_LED_RED_D | 229.78 | 219.75 | 104.56 |
| ENCLO_LED_RED_G | 469.07 | 455.99 | 102.87 |
| ENCLO_LED_RED_R | 296.24 | 197.02 | 150.36000000000001 |
| EXP_BMC_HB_LED_D | 186.83 | 207.75 | 89.93 |
| EXP_BMC_HB_LED_R | 6754.16 | 7779.74 | 86.82 |
| EXP_SMART_RX | 10204.11 | 8537 | 119.53 |
| EXP_SMART_RX_R | 144.03 | 69.06 | 208.56 |
| EXP_SMART_TX | 10223.620000000001 | 8459 | 120.86 |
| EXP_SMART_TX_R | 142.55000000000001 | 78.239999999999995 | 182.2 |
| EXP_TRAY_ID | 14318.8 | 13292.6 | 107.72 |
| EXP_TRAY_ID_BMC | 494.22 | 458.4 | 107.81 |
| EXP_UART_RX_R | 139.07 | 122.7 | 113.34 |
| EXP_UART_TX_R | 85.62 | 106.3 | 80.55 |
| FAN_PWM_PCIE_BMC | 209.69 | 187.67 | 111.73 |
| FCB_HW_REVISION | 7026.43 | 4749.1899999999996 | 147.94999999999999 |
| FLA1_WPN | 10673.27 | 10896.38 | 97.95 |
| FLA1_WPN_R | 228.78 | 277.70999999999998 | 82.38 |
| FLA_CS | 1270.2 | 849.89 | 149.44999999999999 |
| FLA_CS1 | 489.33 | 553.04999999999995 | 88.48 |
| FLA_CS1_R | 4921.8900000000003 | 4411.26 | 111.58 |
| FLA_CS_R | 5722.88 | 5501.14 | 104.03 |
| FLA_WPN | 159.94 | 160.63999999999999 | 99.56 |
| FM_BMC_RESET#_BTN | 25028.65 | 15928.17 | 157.13 |
| FM_BMC_RESET#_BTN_D | 120.78 | 77.5 | 155.85 |
| FM_BMC_RESET_N | 8521 | 6933.65 | 122.89 |
| FM_BMC_RESET_Q36 | 1076.92 | 1227 | 87.77 |
| FM_BMC_RESET_Q36_R | 166.16 | 120.4 | 138.01 |
| FM_OSC_50M_EN | 96.48 | 106.95 | 90.21 |
| FM_PCH_LAN1_DISABLE_N | 2106.61 | 1933.43 | 108.96 |
| FM_PCH_LAN1_DISABLE_N_R | 379.3 | 464.95 | 81.58 |
| FM_TPM_PRES_N | 1003.06 | 1181.45 | 84.9 |
| FM_TPM_PRES_N_R | 297.31 | 303.44 | 97.98 |
| FM_TPM_PRES_RST | 309.19 | 282.77 | 109.34 |
| FM_TPM_PRES_RST_N | 1938.78 | 1956.44 | 99.1 |
| FM_TPM_PRES_RST_N_C | 169.25 | 172.58 | 98.07 |
| FM_TPM_PRES_RST_N_R | 115.98 | 121.5 | 95.45 |
| GND | 83349.179999999993 | 195226.67 | 42.69 |
| GPIO107_R | 55.66 | 0 | 1.#J |
| GPIO108_R | 55.48 | 38.92 | 142.55000000000001 |
| GPIO109_R | 55.68 | 78.739999999999995 | 70.709999999999994 |
| GPIOB1 | 2263.65 | 1766.51 | 128.13999999999999 |
| GPIOH0 | 186.63 | 240.22 | 77.69 |
| GPIOH2 | 69.11 | 70.7 | 97.75 |
| GPIOH2_R | 273.06 | 311.57 | 87.64 |
| GPIOM0_I210_PERST_N | 674.62 | 756.33 | 89.2 |
| GPIOR1_R | 419.92 | 408.06 | 102.91 |
| GPIOR2_R | 376.77 | 385.06 | 97.85 |
| GPIOR3_R | 540.99 | 576.04 | 93.91 |
| GPIOR4_BMC_INT_N_R | 432.39 | 359.56 | 120.25 |
| GPIOR5_R | 380.75 | 336.56 | 113.13 |
| GPIOS5_R | 600.49 | 585.34 | 102.59 |
| HB_A_IN | 564.13 | 565.99 | 99.67 |
| HB_A_OUT | 490.23 | 552.21 | 88.78 |
| HB_OUT | 22013 | 22094.52 | 99.63 |
| HB_OUT_BMC | 11090.75 | 11257.18 | 98.52 |
| HB_OUT_R | 76.11 | 90.4 | 84.19 |
| HIGH_HEX_0 | 11831.14 | 12678.37 | 93.32 |
| HIGH_HEX_1 | 11956.03 | 12851.56 | 93.03 |
| HIGH_HEX_2 | 11988.57 | 12662.61 | 94.68 |
| HIGH_HEX_3 | 12179.36 | 12709.81 | 95.83 |
| HOST1_RST_N | 1800.12 | 1688.1 | 106.64 |
| HOST1_RST_N_C | 2692.38 | 2752.29 | 97.82 |
| HOST1_RST_N_LS | 1053.71 | 988.88 | 106.56 |
| HOST1_RST_N_R | 326.51 | 306.83 | 106.41 |
| HOST2_RST_N | 1584.06 | 1374.62 | 115.24 |
| HOST2_RST_N_C | 1989.18 | 2269.09 | 87.66 |
| HOST2_RST_N_LS | 873.1 | 959.63 | 90.98 |
| HOST3_RST_N | 1598.43 | 1350.87 | 118.33 |
| HOST3_RST_N_C | 1632.83 | 1649.16 | 99.01 |
| HOST3_RST_N_LS | 866.61 | 930.38 | 93.15 |
| HOST4_RST_N | 1616.3 | 1287.0999999999999 | 125.58 |
| HOST4_RST_N_C | 1242.3 | 1093.48 | 113.61 |
| HOST4_RST_N_LS | 854.36 | 901.13 | 94.81 |
| HOST5_RST_N | 2723.6 | 2587.96 | 105.24 |
| HOST5_RST_N_C | 746.3 | 820.18 | 90.99 |
| HOST5_RST_N_LS | 835.47 | 871.83 | 95.83 |
| HOST6_RST_N | 2907.92 | 2582.96 | 112.58 |
| HOST6_RST_N_C | 1189.08 | 1298.25 | 91.59 |
| HOST6_RST_N_LS | 852.61 | 842.58 | 101.19 |
| HOST7_RST_N | 2700.09 | 2368.73 | 113.99 |
| HOST7_RST_N_C | 1935.91 | 1993.66 | 97.1 |
| HOST7_RST_N_LS | 816.3 | 813.33 | 100.37 |
| HOST8_RST_N | 2872.61 | 2466.84 | 116.45 |
| HOST8_RST_N_C | 2316.75 | 2381.73 | 97.27 |
| HOST8_RST_N_LS | 802.69 | 784.08 | 102.37 |
| HOST_I2C_RESET_N | 14437.54 | 12186.5 | 118.47 |
| HOST_I2C_RESET_N_D | 122.86 | 82.5 | 148.91999999999999 |
| HSW_SCL_2 | 184 | 170.9 | 107.66 |
| HSW_SDA_2 | 179.51 | 194.21 | 92.43 |
| I210_CBOT | 166.73 | 115.23 | 144.69 |
| I210_CS_N_R | 1094.99 | 943.03 | 116.11 |
| I210_CTOP | 115.68 | 112.49 | 102.84 |
| I210_PERST_N | 188.53 | 210.42 | 89.6 |
| I210_REFCLK_D_N | 6824.91 | 6225.17 | 109.63 |
| I210_REFCLK_D_P | 6824.52 | 6204.86 | 109.99 |
| I210_SI_R | 1151.5899999999999 | 1193.44 | 96.49 |
| I210_SK_R | 851.18 | 973.27 | 87.46 |
| I210_SO_R | 957.58 | 1048.29 | 91.35 |
| I2C10_BUFF_EN | 123.29 | 89.4 | 137.91 |
| I2C10_BUF_READY | 127.85 | 89.4 | 143.01 |
| I2C1_LS_G1 | 110.31 | 55.5 | 198.76 |
| I2C1_LS_G2 | 122.23 | 60.5 | 202.03 |
| I2C2_LS_G1 | 119.33 | 60.5 | 197.24 |
| I2C2_LS_G2 | 104.14 | 60.5 | 172.13 |
| I2C3_LS_G1 | 94.15 | 55.5 | 169.63 |
| I2C3_LS_G2 | 92.27 | 55.5 | 166.24 |
| I2C4_LS_G1 | 102.48 | 60.5 | 169.39 |
| I2C4_LS_G2 | 107.54 | 55.5 | 193.77 |
| I2C5_BUFF_EN | 123.04 | 104.6 | 117.62 |
| I2C5_LS_G1 | 112.38 | 55.5 | 202.48 |
| I2C5_LS_G2 | 97.56 | 55.5 | 175.79 |
| I2C6_BUFF_EN | 181.15 | 89.4 | 202.63 |
| I2C6_BUF_READY | 121.09 | 89.4 | 135.44999999999999 |
| I2C6_LS_G1 | 105.03 | 74.5 | 140.97999999999999 |
| I2C6_LS_G2 | 96.96 | 55.5 | 174.69 |
| I2C7_BUFF_EN | 121.13 | 89.4 | 135.49 |
| I2C7_BUF_READY | 121.2 | 89.4 | 135.57 |
| I2C7_LS_G1 | 115.27 | 135.5 | 85.07 |
| I2C7_LS_G2 | 96.27 | 67.08 | 143.52000000000001 |
| I2C8_BUFF_EN | 122.09 | 89.4 | 136.56 |
| I2C8_BUF_READY | 122.27 | 89.4 | 136.76 |
| I2C8_LS_G1 | 97.26 | 55.5 | 175.25 |
| I2C8_LS_G2 | 109.7 | 56.5 | 194.16 |
| I2C9_BUFF_EN | 135.08000000000001 | 89.4 | 151.1 |
| I2C9_BUF_READY | 126.37 | 89.4 | 141.35 |
| I2C_GPIO_SCL_1 | 130.31 | 156.9 | 83.05 |
| I2C_GPIO_SCL_2 | 130.31 | 156.9 | 83.05 |
| I2C_GPIO_SCL_3 | 130.31 | 156.9 | 83.05 |
| I2C_GPIO_SCL_4 | 135.59 | 156.9 | 86.42 |
| I2C_GPIO_SDA_1 | 154.38999999999999 | 171.3 | 90.13 |
| I2C_GPIO_SDA_2 | 156.93 | 171.3 | 91.61 |
| I2C_GPIO_SDA_3 | 148.35 | 171.3 | 86.6 |
| I2C_GPIO_SDA_4 | 149.26 | 171.3 | 87.14 |
| I2C_MAX6654_CLK | 263.81 | 306.75 | 86 |
| I2C_MAX6654_DAT | 229.65 | 215.48 | 106.57 |
| I2C_MUX_1A | 109.24 | 128.66 | 84.9 |
| I2C_MUX_2A | 156.44999999999999 | 123.3 | 126.88 |
| I2C_MUX_3A | 93.14 | 93.35 | 99.78 |
| I2C_MUX_4A | 175.52 | 151.66 | 115.73 |
| I2C_MUX_RESET_PEB | 18812.830000000002 | 13506.91 | 139.28 |
| I2C_MUX_RESET_PEB_R | 494.98 | 513.67999999999995 | 96.36 |
| I2C_TPM_SCL | 234.38 | 224.11 | 104.58 |
| I2C_TPM_SDA | 230.52 | 175.79 | 131.13 |
| INVERTER_G1 | 118.11 | 150.38999999999999 | 78.540000000000006 |
| INVERTER_G2 | 231.91 | 137.5 | 168.66 |
| IOEXP1_AD0 | 231.64 | 143.11000000000001 | 161.86000000000001 |
| IOEXP1_AD1 | 425.2 | 181.3 | 234.53 |
| IOEXP1_AD2 | 282 | 166.9 | 168.96 |
| IOEXP2_AD0 | 225.33 | 143.11000000000001 | 157.44999999999999 |
| IOEXP2_AD1 | 289.99 | 181.3 | 159.94999999999999 |
| IOEXP2_AD2 | 272.31 | 166.9 | 163.16 |
| IOEXP3_AD0 | 229.98 | 143.11000000000001 | 160.69999999999999 |
| IOEXP3_AD1 | 273.62 | 186.3 | 146.87 |
| IOEXP3_AD2 | 172.88 | 171.9 | 100.57 |
| IOEXP4_AD0 | 240.09 | 143.11000000000001 | 167.76 |
| IOEXP4_AD1 | 256.17 | 181.3 | 141.30000000000001 |
| IOEXP4_AD2 | 279.02999999999997 | 166.9 | 167.18 |
| IOEXP4_GPIO12 | 236.77 | 260.01 | 91.06 |
| IOEXP4_GPIO13 | 177.52 | 179.41 | 98.94 |
| IOEXP4_GPIO14 | 115.1 | 121.85 | 94.46 |
| IOEXP_INT#_1 | 16044.45 | 13722.22 | 116.92 |
| IOEXP_INT#_2 | 16484.080000000002 | 12066.7 | 136.61000000000001 |
| IOEXP_INT#_3 | 13802.91 | 8307.2199999999993 | 166.16 |
| IOEXP_INT#_4 | 8719.2999999999993 | 9665.5499999999993 | 90.21 |
| IOEXP_PEWAKE# | 151.36000000000001 | 151.9 | 99.64 |
| IOEXP_PMC1_AD0 | 189.04 | 177.5 | 106.5 |
| IOEXP_PMC1_AD1 | 204.77 | 219.3 | 93.38 |
| IOEXP_PMC1_AD2 | 172.82 | 176.1 | 98.14 |
| IOEXP_PMC1_INT# | 5980.63 | 5844.23 | 102.33 |
| IOEXP_TWI_SCL3 | 233.56 | 171.9 | 135.87 |
| IOEXP_TWI_SDA3 | 166.11 | 186.3 | 89.16 |
| IPMB_CLK | 523.05999999999995 | 287.48 | 181.95 |
| IPMB_DAT | 593.16 | 276.2 | 214.76 |
| JTAG_BMC_TCK | 1188.44 | 829.57 | 143.26 |
| JTAG_BMC_TDI | 711.69 | 659.13 | 107.97 |
| JTAG_BMC_TDO | 1366.34 | 1092.56 | 125.06 |
| JTAG_BMC_TMS | 989.35 | 761.07 | 130 |
| JTAG_BMC_TRST_N | 907.23 | 934.08 | 97.13 |
| LAN1_51 | 177.85 | 168.1 | 105.8 |
| LAN1_56 | 161.84 | 175.99 | 91.96 |
| LAN_MAIN_PWR_OK | 129.99 | 156.69 | 82.96 |
| LAN_SE_RSET | 995.64 | 846.11 | 117.67 |
| LAN_SMB_ALERT_N | 1948.03 | 1994.4 | 97.68 |
| LAN_SMB_ALERT_N_R | 577.49 | 618.9 | 93.31 |
| LAN_SMB_CLK | 4230.4799999999996 | 4007.72 | 105.56 |
| LAN_SMB_DAT | 4304.24 | 4085.52 | 105.35 |
| LBI_ADDR_8 | 95.38 | 79.09 | 120.59 |
| LBI_ADDR_9 | 298.8 | 329.8 | 90.6 |
| LBI_ADDR_10 | 67.73 | 44.9 | 150.84 |
| LBI_ADDR_0_R | 871.72 | 892.26 | 97.7 |
| LBI_ADDR_12_R | 95.03 | 39.369999999999997 | 241.39 |
| LBI_ADDR_1_R | 883.08 | 976.63 | 90.42 |
| LBI_ADDR_2_R | 655.56 | 824.78 | 79.48 |
| LBI_ADDR_3_R | 832.67 | 987.89 | 84.29 |
| LBI_ADDR_4_R | 2223.96 | 1072.26 | 207.41 |
| LBI_ADDR_5_R | 1842.11 | 920.41 | 200.14 |
| LBI_ADDR_6_R | 1848.43 | 1004.78 | 183.96 |
| LBI_ADDR_7_R | 1718.11 | 1089.1500000000001 | 157.75 |
| LBI_BYTEN# | 55.67 | 39.369999999999997 | 141.41 |
| LBI_CE#0 | 495.7 | 501.13 | 98.92 |
| LBI_CE#2 | 321.52 | 311.77 | 103.13 |
| LBI_CE#3 | 323.70999999999998 | 342.4 | 94.54 |
| LBI_DATA10 | 55.7 | 39.4 | 141.38 |
| LBI_DATA15 | 561.05999999999995 | 587.5 | 95.5 |
| LBI_DATA11_R | 95.12 | 79.06 | 120.32 |
| LBI_DATA12_R | 749.05 | 758.11 | 98.8 |
| LBI_DATA13_R | 337.24 | 348.22 | 96.85 |
| LBI_DATA14_R | 625.79 | 606.45000000000005 | 103.19 |
| LBI_DATA_0 | 821.1 | 783.5 | 104.8 |
| LBI_DATA_1 | 55.66 | 0 | 1.#J |
| LBI_DATA_2 | 547.04999999999995 | 489.87 | 111.67 |
| LBI_DATA_3 | 55.67 | 39.369999999999997 | 141.41 |
| LBI_DATA_4 | 55.66 | 0 | 1.#J |
| LBI_DATA_5 | 533.34 | 460.61 | 115.79 |
| LBI_DATA_6 | 55.66 | 0 | 1.#J |
| LBI_DATA_7 | 95.04 | 78.739999999999995 | 120.7 |
| LBI_DATA_8 | 902.63 | 774.99 | 116.47 |
| LBI_DATA_9 | 95.15 | 39.68 | 239.79 |
| LBI_OE# | 419.71 | 431.77 | 97.21 |
| LBI_WE# | 55.67 | 39.369999999999997 | 141.41 |
| LED_DR_LED0 | 119.93 | 137.5 | 87.22 |
| LED_DR_LED1 | 11477.15 | 11898.08 | 96.46 |
| LED_MDI0_100M_1G_N | 388.29 | 488.08 | 79.55 |
| LED_MDI0_100M_N | 2137.13 | 2329.52 | 91.74 |
| LED_MDI0_100M_N_R | 279.23 | 354.57 | 78.75 |
| LED_MDI0_1G_N | 1472.63 | 1534.31 | 95.98 |
| LED_MDI0_1G_N_R | 866.12 | 959.47 | 90.27 |
| LED_MDI0_ACT | 1177.6099999999999 | 1097.1300000000001 | 107.34 |
| LED_MDI0_LINK_N | 2557.31 | 2183.5300000000002 | 117.12 |
| LED_PWR_N_ON | 909.79 | 652.16 | 139.5 |
| LED_PWR_N_R | 313.42 | 254.36 | 123.22 |
| LED_Q_1 | 712.14 | 833.1 | 85.48 |
| LED_Q_2 | 1162.8499999999999 | 1273.44 | 91.32 |
| LED_Q_3 | 1305.3800000000001 | 1222.31 | 106.8 |
| LED_Q_4 | 1617.1 | 1556.83 | 103.87 |
| LED_Q_5 | 760.62 | 785.32 | 96.85 |
| LED_Q_6 | 879.73 | 980.56 | 89.72 |
| LED_Q_7 | 1220.4000000000001 | 1381.87 | 88.32 |
| LED_Q_8 | 1327.66 | 1426.1 | 93.1 |
| LED_Q_9 | 1891.42 | 1766.87 | 107.05 |
| LED_Q_10 | 1673.54 | 1823.72 | 91.77 |
| LED_Q_11 | 1545.82 | 1880.57 | 82.2 |
| LED_Q_12 | 1825.2 | 2251.83 | 81.05 |
| LED_Q_13 | 1894.21 | 2199.98 | 86.1 |
| LED_Q_14 | 1952.39 | 2148.13 | 90.89 |
| LED_R_1 | 97.15 | 100.98 | 96.2 |
| LED_R_2 | 96.55 | 99.76 | 96.78 |
| LED_R_3 | 92.48 | 95.44 | 96.89 |
| LED_R_4 | 93.62 | 100.84 | 92.84 |
| LED_R_5 | 50.87 | 59.04 | 86.17 |
| LED_R_6 | 52.09 | 60.26 | 86.45 |
| LED_R_7 | 53.31 | 61.48 | 86.72 |
| LED_R_8 | 54.53 | 62.7 | 86.98 |
| LED_R_9 | 109.01 | 51.24 | 212.75 |
| LED_R_10 | 111.26 | 61.59 | 180.65 |
| LED_R_11 | 95.82 | 87.54 | 109.45 |
| LED_R_12 | 98.79 | 114.79 | 86.06 |
| LED_R_13 | 115.05 | 47.01 | 244.73 |
| LED_R_14 | 96.35 | 46.87 | 205.56 |
| LINK | 55.67 | 39.26 | 141.81 |
| LOW_HEX_0 | 11837.55 | 12804.33 | 92.45 |
| LOW_HEX_1 | 11978.35 | 12851.53 | 93.21 |
| LOW_HEX_2 | 11857.03 | 12757.13 | 92.94 |
| LOW_HEX_3 | 11808.33 | 12741.33 | 92.68 |
| MATED_P12V_EN | 335.3 | 260 | 128.96 |
| MAX6654_ADD0 | 124.49 | 77.45 | 160.72999999999999 |
| MAX6654_ADD1 | 254.94 | 147.1 | 173.31 |
| MAX6654_ALERT# | 207.8 | 191.42 | 108.56 |
| MAX7311_TP301 | 81.569999999999993 | 83.8 | 97.34 |
| MB0_12V_CTRL_GATE1 | 131.1 | 93.5 | 140.21 |
| MB0_CM_ADR1_R | 242.88 | 290.79000000000002 | 83.52 |
| MB0_CM_ADR2_R | 261.76 | 308.10000000000002 | 84.96 |
| MB0_CM_GATE | 833.19 | 847.1 | 98.36 |
| MB0_CM_GATE_R | 349.76 | 340 | 102.87 |
| MB0_CM_OV_R | 333.41 | 408.1 | 81.7 |
| MB0_CM_SENSE_N | 128.99 | 132.79 | 97.14 |
| MB0_CM_SENSE_P | 141.63 | 156.84 | 90.3 |
| MB0_CM_SENSE_R1_N | 1058.67 | 1052.95 | 100.54 |
| MB0_CM_SENSE_R1_P | 1093.4000000000001 | 1077.01 | 101.52 |
| MB0_CM_UV_R | 316.69 | 300.79000000000002 | 105.29 |
| MB0_CM_VOUT_R | 184.92 | 180.16 | 102.64 |
| MB0_HS_ENABLE | 1324.24 | 934 | 141.78 |
| MB0_ISET_R | 334.89 | 331.03 | 101.16 |
| MB0_ISTART_R | 726.19 | 381.34 | 190.43 |
| MB0_P12V_MAIN_R | 0 | 228.82 | 0 |
| MB0_P12V_PWGIN_R | 176.31 | 163.16 | 108.06 |
| MB0_P12V_PWRGOOD | 5879.82 | 6068 | 96.9 |
| MB0_P12V_R | 138.05000000000001 | 87.5 | 157.77000000000001 |
| MB0_PSET_R | 291.44 | 316.10000000000002 | 92.2 |
| MB0_RETRY_R | 207.03 | 233.1 | 88.82 |
| MB0_SPISS_PD | 178.17 | 208.1 | 85.62 |
| MB0_TEMP | 202.56 | 201.1 | 100.73 |
| MB0_TEMP_C | 225.32 | 100.28 | 224.69 |
| MB0_TEMP_E | 111.77 | 60.72 | 184.07 |
| MB0_TIME_R | 229.14 | 290.16000000000003 | 78.97 |
| MB0_VCAP_R | 353.08 | 362.29 | 97.46 |
| MB0_VCC | 254.99 | 219.53 | 116.15 |
| MBP_UART_RX | 5392.71 | 4260.1000000000004 | 126.59 |
| MBP_UART_TX | 5800.08 | 4209.6000000000004 | 137.78 |
| MDC | 95.17 | 39.54 | 240.69 |
| MDIO | 1129.6199999999999 | 1212.9100000000001 | 93.13 |
| MEMA_0 | 1043.55 | 812.27 | 128.47 |
| MEMA_1 | 1039.1500000000001 | 780.78 | 133.09 |
| MEMA_2 | 1054.58 | 938.26 | 112.4 |
| MEMA_3 | 1033.53 | 843.77 | 122.49 |
| MEMA_4 | 1052.67 | 654.79 | 160.76 |
| MEMA_5 | 1048.1600000000001 | 906.77 | 115.59 |
| MEMA_6 | 1040.46 | 717.78 | 144.96 |
| MEMA_7 | 1059.9100000000001 | 780.78 | 135.75 |
| MEMA_8 | 1065.8399999999999 | 686.29 | 155.30000000000001 |
| MEMA_9 | 1055.48 | 812.27 | 129.94 |
| MEMA_10 | 1028.49 | 654.79 | 157.07 |
| MEMA_11 | 1058.24 | 717.79 | 147.43 |
| MEMA_12 | 1092.57 | 686.29 | 159.19999999999999 |
| MEMA_13 | 1055.1500000000001 | 875.26 | 120.55 |
| MEMA_14 | 1054.22 | 686.29 | 153.61000000000001 |
| MEMBA_0 | 1037.9100000000001 | 906.77 | 114.46 |
| MEMBA_1 | 1054.42 | 686.29 | 153.63999999999999 |
| MEMBA_2 | 1041.46 | 843.77 | 123.43 |
| MEMCASN | 1044.02 | 749.28 | 139.34 |
| MEMCKE | 1100.68 | 654.79 | 168.1 |
| MEMCK_N | 1076.0899999999999 | 686.29 | 156.80000000000001 |
| MEMCK_P | 1074.9100000000001 | 623.29999999999995 | 172.45 |
| MEMCSN | 1144.29 | 843.78 | 135.61000000000001 |
| MEMDM_0 | 1038.9000000000001 | 654.79 | 158.66 |
| MEMDM_1 | 1065.32 | 843.78 | 126.26 |
| MEMDQS_N0 | 1041.8900000000001 | 780.78 | 133.44 |
| MEMDQS_N1 | 1043.93 | 533.78 | 195.57 |
| MEMDQS_P0 | 1039.6300000000001 | 717.78 | 144.84 |
| MEMDQS_P1 | 1045.02 | 591.80999999999995 | 176.58 |
| MEMDQ_0 | 1044.01 | 686.29 | 152.12 |
| MEMDQ_1 | 1033.76 | 843.77 | 122.52 |
| MEMDQ_2 | 1046.82 | 528.80999999999995 | 197.96 |
| MEMDQ_3 | 1057.52 | 591.80999999999995 | 178.69 |
| MEMDQ_4 | 1050.33 | 780.78 | 134.52000000000001 |
| MEMDQ_5 | 1042.78 | 843.78 | 123.58 |
| MEMDQ_6 | 1063.01 | 717.79 | 148.09 |
| MEMDQ_7 | 1040.18 | 749.27 | 138.83000000000001 |
| MEMDQ_8 | 1046.6400000000001 | 659.78 | 158.63 |
| MEMDQ_9 | 1043.56 | 533.78 | 195.5 |
| MEMDQ_10 | 1036.32 | 628.28 | 164.95 |
| MEMDQ_11 | 1050.72 | 722.76 | 145.38 |
| MEMDQ_12 | 1029.73 | 785.76 | 131.05000000000001 |
| MEMDQ_13 | 1055.5999999999999 | 628.28 | 168.01 |
| MEMDQ_14 | 1051.1600000000001 | 754.25 | 139.36000000000001 |
| MEMDQ_15 | 1064.3900000000001 | 817.25 | 130.24 |
| MEMODT | 1131.6600000000001 | 906.76 | 124.8 |
| MEMRASN | 1063.3 | 812.28 | 130.9 |
| MEMWEN | 1055.93 | 843.77 | 125.14 |
| MINISAS_CN15_A_I2C_INT# | 1061.78 | 1154.98 | 91.93 |
| MINISAS_CN15_B_I2C_INT# | 2668.95 | 2796.78 | 95.43 |
| MINISAS_CN15_C_I2C_INT# | 1014.63 | 871.18 | 116.47 |
| MINISAS_CN15_D_I2C_INT# | 927.87 | 876.82 | 105.82 |
| MINISAS_CN16_A_I2C_INT# | 4023.93 | 3521.8 | 114.26 |
| MINISAS_CN16_B_I2C_INT# | 4141.38 | 3794.48 | 109.14 |
| MINISAS_CN16_C_I2C_INT# | 3609.52 | 3411.72 | 105.8 |
| MINISAS_CN16_D_I2C_INT# | 6146.24 | 5142.46 | 119.52 |
| MNG_RX_DN | 2795.66 | 3019.42 | 92.59 |
| MNG_RX_DP | 2792.81 | 2834.74 | 98.52 |
| MNG_TX_DN | 2953.55 | 3281.42 | 90.01 |
| MNG_TX_DP | 2953.27 | 3176.74 | 92.97 |
| MPLLAV33 | 987.17 | 1032.04 | 95.65 |
| NCSI_10G_RCLK | 113.41 | 152.27000000000001 | 74.48 |
| NCSI_ARB_IN | 84.47 | 89.62 | 94.25 |
| NCSI_ARB_OUT | 98.04 | 120.7 | 81.22 |
| NIC0_CT_POWER | 440.22 | 1340.04 | 32.85 |
| NIC0_MDI0_N0 | 1272.98 | 985.67 | 129.15 |
| NIC0_MDI0_N1 | 1156.94 | 861.12 | 134.35 |
| NIC0_MDI0_N2 | 948.9 | 827.91 | 114.61 |
| NIC0_MDI0_N3 | 1101.01 | 1047.97 | 105.06 |
| NIC0_MDI0_N0_R | 325.83999999999997 | 335.53 | 97.11 |
| NIC0_MDI0_N1_R | 355.1 | 302.57 | 117.36 |
| NIC0_MDI0_N2_R | 433.1 | 365.81 | 118.39 |
| NIC0_MDI0_N3_R | 348.53 | 350.37 | 99.48 |
| NIC0_MDI0_P0 | 1275.3800000000001 | 1045.3599999999999 | 122 |
| NIC0_MDI0_P1 | 1156.95 | 840.8 | 137.6 |
| NIC0_MDI0_P2 | 946.8 | 768.23 | 123.24 |
| NIC0_MDI0_P3 | 1100.06 | 1068.28 | 102.97 |
| NIC0_MDI0_P0_R | 325.37 | 300.61 | 108.24 |
| NIC0_MDI0_P1_R | 355.87 | 274.39 | 129.69 |
| NIC0_MDI0_P2_R | 433.26 | 399.73 | 108.39 |
| NIC0_MDI0_P3_R | 348.1 | 315.45 | 110.35 |
| NIC_JTCK | 291.74 | 346.06 | 84.3 |
| NIC_JTDI | 141.75 | 169.91 | 83.42 |
| NIC_JTDO | 228.46 | 259.75 | 87.95 |
| NIC_JTMS | 301.56 | 368.19 | 81.900000000000006 |
| NVM_CS_N | 246.58 | 295.38 | 83.48 |
| NVM_CS_N_R | 1999.69 | 2360.12 | 84.73 |
| NVM_SI | 180.16 | 224.33 | 80.31 |
| NVM_SI_R | 2302.92 | 2141.62 | 107.53 |
| NVM_SK | 202.41 | 245.45 | 82.46 |
| NVM_SK_R | 2172.4 | 2339.33 | 92.86 |
| NVM_SO | 320.08 | 271.06 | 118.08 |
| NVM_SO_R | 1634.24 | 1935.76 | 84.42 |
| OSC0_AS_CLKIN | 369.04 | 414.07 | 89.12 |
| OSC2_CONT | 94.48 | 98.86 | 95.57 |
| OSC2_OUT | 68.89 | 68.900000000000006 | 99.98 |
| P0V9 | 6781.86 | 8452.8700000000008 | 80.23 |
| P0V9_E | 16039.06 | 15351.86 | 104.48 |
| P0V9_EN | 261.38 | 200.83 | 130.15 |
| P0V9_E_EN | 301.27999999999997 | 279.83 | 107.67 |
| P0V9_E_LX | 680.28 | 806.71 | 84.33 |
| P0V9_E_MODE | 266.63 | 229.51 | 116.18 |
| P0V9_E_PG | 15590.73 | 14840.8 | 105.05 |
| P0V9_E_RF | 291.97000000000003 | 287.14 | 101.68 |
| P0V9_E_SNB | 56.57 | 59.5 | 95.08 |
| P0V9_E_SW_R | 359.43 | 365 | 98.47 |
| P0V9_E_TRIP | 186.57 | 169.83 | 109.86 |
| P0V9_E_VBST | 87.42 | 91.44 | 95.6 |
| P0V9_E_VBST_RC | 50.66 | 53 | 95.58 |
| P0V9_E_VDD | 258.27 | 297.44 | 86.83 |
| P0V9_E_VFB | 437.65 | 368.14 | 118.88 |
| P0V9_E_VFB_AVS | 279.69 | 192.5 | 145.29 |
| P0V9_E_VFB_R | 125.24 | 127 | 98.62 |
| P0V9_E_VIN | 0 | 1419.81 | 0 |
| P0V9_E_VREG | 211.55 | 163.88 | 129.09 |
| P0V9_I210 | 486.94 | 1470.29 | 33.119999999999997 |
| P0V9_LX | 455.96 | 660.57 | 69.02 |
| P0V9_MODE | 240.66 | 193.51 | 124.36 |
| P0V9_PG | 11096.63 | 7793.29 | 142.38999999999999 |
| P0V9_RF | 480.54 | 355.69 | 135.1 |
| P0V9_SNB | 60.71 | 69.5 | 87.36 |
| P0V9_SW_R | 333.74 | 359 | 92.96 |
| P0V9_TRIP | 181.21 | 133.83000000000001 | 135.4 |
| P0V9_VBST | 140.36000000000001 | 124.7 | 112.56 |
| P0V9_VBST_RC | 52.07 | 55 | 94.67 |
| P0V9_VDD | 312.45999999999998 | 200.35 | 155.96 |
| P0V9_VFB | 337.11 | 330.14 | 102.11 |
| P0V9_VFB_AVS | 244.27 | 248.34 | 98.36 |
| P0V9_VFB_R | 165.83 | 166 | 99.9 |
| P0V9_VIN | 0 | 1504.1 | 0 |
| P0V9_VREG | 190.8 | 179.19 | 106.48 |
| P12V | 7625.09 | 25982.7 | 29.35 |
| P12V_PCIE | 11707.23 | 9965.56 | 117.48 |
| P1V26_PWR | 27.4 | 535.79999999999995 | 5.1100000000000003 |
| P1V26_STBY | 4228.1099999999997 | 5197.95 | 81.34 |
| P1V53_PWR | 186.1 | 574.5 | 32.39 |
| P1V53_STBY | 3560.06 | 5811.64 | 61.26 |
| P1V5_I210 | 794.95 | 1257.18 | 63.23 |
| P1V8_CLKGEN | 1517.19 | 1800.48 | 84.27 |
| P1V8_CLKGEN_A | 254.67 | 146.37 | 173.99 |
| P1V8_PWR | 36.06 | 793.49 | 4.54 |
| P1V8_STBY | 8466.69 | 7858.18 | 107.74 |
| P3V0_BAT | 715.44 | 724.52 | 98.75 |
| P3V0_BAT_R | 77.650000000000006 | 87.92 | 88.31 |
| P3V3_GPIO | 1837.9 | 1682.82 | 109.22 |
| P3V3_I2C_MUX | 225.02 | 216.33 | 104.02 |
| P3V3_PWR | 1034.8499999999999 | 1331 | 77.75 |
| P3V3_RTC | 843.73 | 867.37 | 97.27 |
| P3V3_STBY | 58432.78 | 99676.03 | 58.62 |
| P3V3_STBY_EN | 238.02 | 192.33 | 123.76 |
| P3V3_STBY_LL | 370.46 | 531.9 | 69.650000000000006 |
| P3V3_STBY_LL_R | 283.49 | 290 | 97.76 |
| P3V3_STBY_MODE | 257.83 | 227.01 | 113.58 |
| P3V3_STBY_PG | 6038.81 | 5742.67 | 105.16 |
| P3V3_STBY_RF | 444.39 | 275.70999999999998 | 161.18 |
| P3V3_STBY_ROVP | 164.29 | 168.28 | 97.63 |
| P3V3_STBY_SNB | 64.73 | 70 | 92.47 |
| P3V3_STBY_TRIP | 177.08 | 167.33 | 105.83 |
| P3V3_STBY_VBST | 109.12 | 121.2 | 90.03 |
| P3V3_STBY_VBST_RC | 65.94 | 80 | 82.43 |
| P3V3_STBY_VDD | 284.5 | 292.94 | 97.12 |
| P3V3_STBY_VFB | 298.16000000000003 | 327.64 | 91 |
| P3V3_STBY_VFB_R | 121.07 | 87.5 | 138.37 |
| P3V3_STBY_VIN | 0 | 662.79 | 0 |
| P3V3_STBY_VREG | 206.63 | 162.71 | 126.99 |
| P5V_STBY | 23055.75 | 21687.34 | 106.31 |
| P5V_STBY_BS | 140.4 | 83.5 | 168.15 |
| P5V_STBY_BS_RC | 117.04 | 45 | 260.08999999999997 |
| P5V_STBY_EN | 244.23 | 168 | 145.37 |
| P5V_STBY_FB | 219.5 | 241.94 | 90.73 |
| P5V_STBY_LR | 440.22 | 872.94 | 50.43 |
| P5V_STBY_LX | 223.84 | 379.84 | 58.93 |
| P5V_USB | 303.8 | 1347.67 | 22.54 |
| P5V_USB_BP1_F | 0 | 586.79999999999995 | 0 |
| PCIE_CLKGEN2_OE0 | 95 | 95 | 100 |
| PCIE_CLKGEN2_OE0_R | 100.72 | 94.73 | 106.32 |
| PCIE_DIS | 236.86 | 220.41 | 107.46 |
| PCIE_MATED#_A | 5168.96 | 4014.28 | 128.76 |
| PCIE_MATED#_B | 13256.73 | 11581.11 | 114.47 |
| PCIE_REFCLK_D_N | 4578.92 | 4925.5 | 92.96 |
| PCIE_REFCLK_D_N_R | 112.86 | 135.04 | 83.58 |
| PCIE_REFCLK_D_P | 4578.5200000000004 | 4943.5 | 92.62 |
| PCIE_REFCLK_D_P_R | 112.86 | 114.73 | 98.37 |
| PCIE_REFCLK_H0_N | 2044.84 | 2356.75 | 86.77 |
| PCIE_REFCLK_H0_N_R | 640.77 | 730.47 | 87.72 |
| PCIE_REFCLK_H0_P | 2044.99 | 2356.12 | 86.8 |
| PCIE_REFCLK_H0_P_R | 641.07000000000005 | 716.06 | 89.53 |
| PCIE_REFCLK_H1_N | 2253.42 | 2599.88 | 86.67 |
| PCIE_REFCLK_H1_N_R | 1703.37 | 1761.61 | 96.69 |
| PCIE_REFCLK_H1_P | 2254.33 | 2616.62 | 86.15 |
| PCIE_REFCLK_H1_P_R | 1704.31 | 1747.21 | 97.54 |
| PCIE_REFCLK_H2_N | 3251.44 | 3365.79 | 96.6 |
| PCIE_REFCLK_H2_N_R | 2307.89 | 2079.87 | 110.96 |
| PCIE_REFCLK_H2_P | 3251.76 | 3447.06 | 94.33 |
| PCIE_REFCLK_H2_P_R | 2307.4299999999998 | 2206.2199999999998 | 104.59 |
| PCIE_REFCLK_H3_N | 3133.1 | 3053.85 | 102.6 |
| PCIE_REFCLK_H3_N_R | 1486.23 | 1053.31 | 141.1 |
| PCIE_REFCLK_H3_P | 3132.67 | 3134.22 | 99.95 |
| PCIE_REFCLK_H3_P_R | 1486.06 | 1101.57 | 134.9 |
| PCIE_REFCLK_S1_N | 11325.24 | 12608.05 | 89.83 |
| PCIE_REFCLK_S1_P | 11325.68 | 12600.17 | 89.89 |
| PCIE_REFCLK_S2_N | 10815.48 | 12575.8 | 86 |
| PCIE_REFCLK_S2_P | 10815.07 | 12504.94 | 86.49 |
| PCIE_REFCLK_S3_N | 11897.06 | 15071.86 | 78.94 |
| PCIE_REFCLK_S3_P | 11896.73 | 15001 | 79.31 |
| PCIE_REFCLK_S4_N | 12250.55 | 15041.12 | 81.45 |
| PCIE_REFCLK_S4_P | 12250.8 | 14970.25 | 81.83 |
| PCIE_REFCLK_S5_N | 10329.67 | 11130.97 | 92.8 |
| PCIE_REFCLK_S5_P | 10329.24 | 11125.72 | 92.84 |
| PCIE_RX_CAP_N78 | 150.78 | 172.75 | 87.28 |
| PCIE_RX_CAP_P78 | 150.25 | 158.43 | 94.84 |
| PCIE_RX_N0 | 3034.17 | 2519.85 | 120.41 |
| PCIE_RX_N1 | 2669.7 | 2370.2399999999998 | 112.63 |
| PCIE_RX_N2 | 2275.35 | 2380.09 | 95.6 |
| PCIE_RX_N3 | 2244.66 | 2529.6999999999998 | 88.73 |
| PCIE_RX_N4 | 2726.34 | 2795.44 | 97.53 |
| PCIE_RX_N5 | 2545.6 | 2645.83 | 96.21 |
| PCIE_RX_N6 | 2544.16 | 2655.68 | 95.8 |
| PCIE_RX_N7 | 2831.19 | 2805.29 | 100.92 |
| PCIE_RX_N8 | 2818.52 | 3031.67 | 92.97 |
| PCIE_RX_N9 | 2860.58 | 2960.8 | 96.62 |
| PCIE_RX_N10 | 2822.77 | 3049.38 | 92.57 |
| PCIE_RX_N11 | 3130.7 | 3277.73 | 95.51 |
| PCIE_RX_N12 | 3463.7 | 3622.22 | 95.62 |
| PCIE_RX_N13 | 3566.44 | 3551.35 | 100.43 |
| PCIE_RX_N14 | 3734.83 | 3639.93 | 102.61 |
| PCIE_RX_N15 | 4115.42 | 3868.28 | 106.39 |
| PCIE_RX_N16 | 8640.8700000000008 | 10575.81 | 81.7 |
| PCIE_RX_N17 | 8575.94 | 10449.83 | 82.07 |
| PCIE_RX_N18 | 8405.51 | 10245.1 | 82.04 |
| PCIE_RX_N19 | 8345.36 | 10119.120000000001 | 82.47 |
| PCIE_RX_N20 | 8219.74 | 9914.4 | 82.91 |
| PCIE_RX_N21 | 8118.93 | 9788.41 | 82.94 |
| PCIE_RX_N22 | 7982.56 | 9583.69 | 83.29 |
| PCIE_RX_N23 | 7922.3 | 9457.7000000000007 | 83.77 |
| PCIE_RX_N24 | 7783.6 | 9213.61 | 84.48 |
| PCIE_RX_N25 | 7688.41 | 9087.6200000000008 | 84.6 |
| PCIE_RX_N26 | 7524.42 | 8693.92 | 86.55 |
| PCIE_RX_N27 | 7465.37 | 8567.94 | 87.13 |
| PCIE_RX_N28 | 7346.78 | 8268.73 | 88.85 |
| PCIE_RX_N29 | 7274.56 | 8142.74 | 89.34 |
| PCIE_RX_N30 | 7133.65 | 7938.02 | 89.87 |
| PCIE_RX_N31 | 7079.72 | 7812.03 | 90.63 |
| PCIE_RX_N32 | 6740.71 | 7410.46 | 90.96 |
| PCIE_RX_N33 | 6773.41 | 7363.22 | 91.99 |
| PCIE_RX_N34 | 6726.49 | 7237.23 | 92.94 |
| PCIE_RX_N35 | 6762.83 | 7189.99 | 94.06 |
| PCIE_RX_N36 | 6652.69 | 6938.02 | 95.89 |
| PCIE_RX_N37 | 6659.47 | 6890.77 | 96.64 |
| PCIE_RX_N38 | 6968.17 | 7843.52 | 88.84 |
| PCIE_RX_N39 | 6996.77 | 7969.5 | 87.79 |
| PCIE_RX_N40 | 7000.02 | 8103.36 | 86.38 |
| PCIE_RX_N41 | 7098.29 | 8229.34 | 86.26 |
| PCIE_RX_N42 | 7074.72 | 8276.59 | 85.48 |
| PCIE_RX_N43 | 7104.56 | 8402.57 | 84.55 |
| PCIE_RX_N44 | 7058.08 | 8449.82 | 83.53 |
| PCIE_RX_N45 | 7135.15 | 8575.7999999999993 | 83.2 |
| PCIE_RX_N46 | 7117.78 | 8623.0499999999993 | 82.54 |
| PCIE_RX_N47 | 7434.27 | 8938.01 | 83.18 |
| PCIE_RX_N48 | 7320.03 | 8985.25 | 81.47 |
| PCIE_RX_N49 | 7327.89 | 9032.49 | 81.13 |
| PCIE_RX_N50 | 7367.08 | 9158.48 | 80.44 |
| PCIE_RX_N51 | 7359.25 | 9205.7199999999993 | 79.94 |
| PCIE_RX_N52 | 7521.85 | 9426.2000000000007 | 79.8 |
| PCIE_RX_N53 | 7456.64 | 9473.44 | 78.709999999999994 |
| PCIE_RX_N54 | 7542.08 | 9599.42 | 78.569999999999993 |
| PCIE_RX_N55 | 7503.53 | 9646.67 | 77.78 |
| PCIE_RX_N56 | 7650.45 | 9733.2800000000007 | 78.599999999999994 |
| PCIE_RX_N57 | 7531.65 | 9780.5300000000007 | 77.010000000000005 |
| PCIE_RX_N58 | 7599.62 | 9906.51 | 76.709999999999994 |
| PCIE_RX_N59 | 7595.72 | 9953.76 | 76.31 |
| PCIE_RX_N60 | 8536.32 | 11166.36 | 76.45 |
| PCIE_RX_N61 | 8530.83 | 11213.6 | 76.08 |
| PCIE_RX_N62 | 8616.73 | 11339.58 | 75.989999999999995 |
| PCIE_RX_N63 | 8644.6200000000008 | 11386.83 | 75.92 |
| PCIE_RX_N64 | 9032.61 | 11882.89 | 76.010000000000005 |
| PCIE_RX_N65 | 9127.6299999999992 | 12008.87 | 76.010000000000005 |
| PCIE_RX_N66 | 9285.89 | 12213.6 | 76.03 |
| PCIE_RX_N67 | 9382.23 | 12339.58 | 76.03 |
| PCIE_RX_N68 | 9621.0499999999993 | 12544.31 | 76.7 |
| PCIE_RX_N69 | 9781.39 | 12796.28 | 76.44 |
| PCIE_RX_N70 | 10031.85 | 13001 | 77.16 |
| PCIE_RX_N71 | 10150.99 | 13126.98 | 77.33 |
| PCIE_RX_N72 | 10366.69 | 13465.57 | 76.989999999999995 |
| PCIE_RX_N73 | 10445.99 | 13591.55 | 76.86 |
| PCIE_RX_N74 | 10617.87 | 13796.28 | 76.959999999999994 |
| PCIE_RX_N75 | 10724.36 | 13922.26 | 77.03 |
| PCIE_RX_N76 | 666.91 | 634.78 | 105.06 |
| PCIE_RX_N78 | 10259.31 | 9659.48 | 106.21 |
| PCIE_RX_N80 | 4960 | 4682.5 | 105.93 |
| PCIE_RX_N81 | 4601.13 | 4454.1499999999996 | 103.3 |
| PCIE_RX_N82 | 4287.53 | 4365.5600000000004 | 98.21 |
| PCIE_RX_N83 | 4460.3599999999997 | 4436.43 | 100.54 |
| PCIE_RX_N84 | 4262.38 | 4091.95 | 104.16 |
| PCIE_RX_N85 | 3892.46 | 3863.6 | 100.75 |
| PCIE_RX_N86 | 3550.27 | 3775.01 | 94.05 |
| PCIE_RX_N87 | 3796.49 | 3845.88 | 98.72 |
| PCIE_RX_N88 | 3832.2 | 3619.5 | 105.88 |
| PCIE_RX_N89 | 3439.94 | 3469.89 | 99.14 |
| PCIE_RX_N90 | 3400.24 | 3460.05 | 98.27 |
| PCIE_RX_N91 | 3483.27 | 3609.66 | 96.5 |
| PCIE_RX_N92 | 3509.91 | 3343.91 | 104.96 |
| PCIE_RX_N93 | 3146.48 | 3194.3 | 98.5 |
| PCIE_RX_N94 | 3093.86 | 3184.46 | 97.15 |
| PCIE_RX_N95 | 3183.8 | 3334.07 | 95.49 |
| PCIE_RX_P0 | 3035.09 | 2474.58 | 122.65 |
| PCIE_RX_P1 | 2670.32 | 2324.98 | 114.85 |
| PCIE_RX_P2 | 2274.42 | 2334.8200000000002 | 97.41 |
| PCIE_RX_P3 | 2244.1 | 2484.42 | 90.33 |
| PCIE_RX_P4 | 2726.94 | 2750.17 | 99.16 |
| PCIE_RX_P5 | 2544.8200000000002 | 2600.5700000000002 | 97.86 |
| PCIE_RX_P6 | 2544.83 | 2610.41 | 97.49 |
| PCIE_RX_P7 | 2830.92 | 2760.01 | 102.57 |
| PCIE_RX_P8 | 2818.69 | 2986.39 | 94.38 |
| PCIE_RX_P9 | 2861.04 | 2915.53 | 98.13 |
| PCIE_RX_P10 | 2822.92 | 3004.11 | 93.97 |
| PCIE_RX_P11 | 3131.25 | 3232.45 | 96.87 |
| PCIE_RX_P12 | 3463.57 | 3576.94 | 96.83 |
| PCIE_RX_P13 | 3566.7 | 3506.08 | 101.73 |
| PCIE_RX_P14 | 3735.3 | 3594.66 | 103.91 |
| PCIE_RX_P15 | 4115.6099999999997 | 3823 | 107.65 |
| PCIE_RX_P16 | 8640.84 | 10583.69 | 81.64 |
| PCIE_RX_P17 | 8575.36 | 10457.700000000001 | 82 |
| PCIE_RX_P18 | 8405.48 | 10252.98 | 81.98 |
| PCIE_RX_P19 | 8345.26 | 10126.99 | 82.41 |
| PCIE_RX_P20 | 8220.6 | 9922.27 | 82.85 |
| PCIE_RX_P21 | 8118.41 | 9796.2900000000009 | 82.87 |
| PCIE_RX_P22 | 7982.54 | 9591.56 | 83.22 |
| PCIE_RX_P23 | 7921.95 | 9465.58 | 83.69 |
| PCIE_RX_P24 | 7784.31 | 9221.48 | 84.41 |
| PCIE_RX_P25 | 7687.99 | 9095.5 | 84.53 |
| PCIE_RX_P26 | 7523.97 | 8701.7999999999993 | 86.46 |
| PCIE_RX_P27 | 7464.53 | 8575.81 | 87.04 |
| PCIE_RX_P28 | 7346.38 | 8276.6 | 88.76 |
| PCIE_RX_P29 | 7274.68 | 8150.62 | 89.25 |
| PCIE_RX_P30 | 7134.48 | 7945.89 | 89.79 |
| PCIE_RX_P31 | 7079.45 | 7819.91 | 90.53 |
| PCIE_RX_P32 | 6739.97 | 7418.33 | 90.86 |
| PCIE_RX_P33 | 6773.19 | 7371.09 | 91.89 |
| PCIE_RX_P34 | 6725.96 | 7245.11 | 92.83 |
| PCIE_RX_P35 | 6762.53 | 7197.86 | 93.95 |
| PCIE_RX_P36 | 6651.97 | 6945.89 | 95.77 |
| PCIE_RX_P37 | 6658.88 | 6898.65 | 96.52 |
| PCIE_RX_P38 | 6968.17 | 7914.38 | 88.04 |
| PCIE_RX_P39 | 6997.13 | 8040.37 | 87.02 |
| PCIE_RX_P40 | 6999.66 | 8174.23 | 85.63 |
| PCIE_RX_P41 | 7098.7 | 8300.2099999999991 | 85.52 |
| PCIE_RX_P42 | 7074.89 | 8347.4500000000007 | 84.76 |
| PCIE_RX_P43 | 7104.29 | 8473.44 | 83.84 |
| PCIE_RX_P44 | 7058.21 | 8520.68 | 82.84 |
| PCIE_RX_P45 | 7135.01 | 8646.67 | 82.52 |
| PCIE_RX_P46 | 7117.68 | 8693.91 | 81.87 |
| PCIE_RX_P47 | 7433.95 | 9008.8700000000008 | 82.52 |
| PCIE_RX_P48 | 7320.07 | 9056.1200000000008 | 80.83 |
| PCIE_RX_P49 | 7328.51 | 9103.36 | 80.5 |
| PCIE_RX_P50 | 7367.6 | 9229.35 | 79.83 |
| PCIE_RX_P51 | 7359.47 | 9276.59 | 79.33 |
| PCIE_RX_P52 | 7521.64 | 9497.06 | 79.2 |
| PCIE_RX_P53 | 7456.54 | 9544.31 | 78.13 |
| PCIE_RX_P54 | 7542.24 | 9670.2900000000009 | 77.989999999999995 |
| PCIE_RX_P55 | 7504.21 | 9717.5300000000007 | 77.22 |
| PCIE_RX_P56 | 7650.5 | 9804.15 | 78.03 |
| PCIE_RX_P57 | 7532.51 | 9851.39 | 76.459999999999994 |
| PCIE_RX_P58 | 7600.38 | 9977.3799999999992 | 76.180000000000007 |
| PCIE_RX_P59 | 7595.03 | 10024.620000000001 | 75.760000000000005 |
| PCIE_RX_P60 | 8535.57 | 11237.22 | 75.959999999999994 |
| PCIE_RX_P61 | 8530.02 | 11284.47 | 75.59 |
| PCIE_RX_P62 | 8616.52 | 11410.45 | 75.510000000000005 |
| PCIE_RX_P63 | 8644.06 | 11457.69 | 75.44 |
| PCIE_RX_P64 | 9032.0499999999993 | 11953.76 | 75.56 |
| PCIE_RX_P65 | 9127.23 | 12079.74 | 75.56 |
| PCIE_RX_P66 | 9286.2099999999991 | 12284.47 | 75.59 |
| PCIE_RX_P67 | 9383.01 | 12410.45 | 75.61 |
| PCIE_RX_P68 | 9621.49 | 12615.17 | 76.27 |
| PCIE_RX_P69 | 9780.9599999999991 | 12867.14 | 76.02 |
| PCIE_RX_P70 | 10032.16 | 13071.87 | 76.75 |
| PCIE_RX_P71 | 10151.18 | 13197.85 | 76.92 |
| PCIE_RX_P72 | 10365.92 | 13536.43 | 76.58 |
| PCIE_RX_P73 | 10446.34 | 13662.42 | 76.459999999999994 |
| PCIE_RX_P74 | 10617.44 | 13867.14 | 76.569999999999993 |
| PCIE_RX_P75 | 10724.85 | 13993.13 | 76.64 |
| PCIE_RX_P76 | 666.85 | 639.15 | 104.33 |
| PCIE_RX_P78 | 10260.1 | 9732.85 | 105.42 |
| PCIE_RX_P80 | 4960.47 | 4696.2700000000004 | 105.63 |
| PCIE_RX_P81 | 4601.58 | 4467.93 | 102.99 |
| PCIE_RX_P82 | 4286.6899999999996 | 4379.3500000000004 | 97.88 |
| PCIE_RX_P83 | 4460 | 4450.21 | 100.22 |
| PCIE_RX_P84 | 4263.2 | 4105.72 | 103.84 |
| PCIE_RX_P85 | 3892.44 | 3877.38 | 100.39 |
| PCIE_RX_P86 | 3550.96 | 3788.8 | 93.72 |
| PCIE_RX_P87 | 3795.74 | 3859.66 | 98.34 |
| PCIE_RX_P88 | 3832.66 | 3633.28 | 105.49 |
| PCIE_RX_P89 | 3440.34 | 3483.68 | 98.76 |
| PCIE_RX_P90 | 3400.82 | 3473.84 | 97.9 |
| PCIE_RX_P91 | 3483.87 | 3623.44 | 96.15 |
| PCIE_RX_P92 | 3510.64 | 3357.69 | 104.56 |
| PCIE_RX_P93 | 3146.99 | 3208.09 | 98.1 |
| PCIE_RX_P94 | 3093.67 | 3198.25 | 96.73 |
| PCIE_RX_P95 | 3183.8 | 3347.85 | 95.1 |
| PCIE_TX_CAP_N0 | 1403.74 | 1543.09 | 90.97 |
| PCIE_TX_CAP_N1 | 1390.92 | 1438.09 | 96.72 |
| PCIE_TX_CAP_N2 | 1858.62 | 1429.15 | 130.05000000000001 |
| PCIE_TX_CAP_N3 | 2040.12 | 1513.41 | 134.80000000000001 |
| PCIE_TX_CAP_N4 | 2095.91 | 1714.02 | 122.28 |
| PCIE_TX_CAP_N5 | 2301.4299999999998 | 1837.55 | 125.24 |
| PCIE_TX_CAP_N6 | 2235.6999999999998 | 1924.5 | 116.17 |
| PCIE_TX_CAP_N7 | 2215.8000000000002 | 1930.93 | 114.75 |
| PCIE_TX_CAP_N8 | 2337.34 | 1900.17 | 123.01 |
| PCIE_TX_CAP_N9 | 2497.69 | 2152.11 | 116.06 |
| PCIE_TX_CAP_N10 | 2564.64 | 2240.69 | 114.46 |
| PCIE_TX_CAP_N11 | 2703.37 | 2407.46 | 112.29 |
| PCIE_TX_CAP_N12 | 2894.99 | 2598.71 | 111.4 |
| PCIE_TX_CAP_N13 | 3050.72 | 2831.63 | 107.74 |
| PCIE_TX_CAP_N14 | 3159.06 | 2925.33 | 107.99 |
| PCIE_TX_CAP_N15 | 3273.85 | 3099.84 | 105.61 |
| PCIE_TX_CAP_N16 | 7918.96 | 9975.75 | 79.38 |
| PCIE_TX_CAP_N17 | 7878.84 | 9849.77 | 79.989999999999995 |
| PCIE_TX_CAP_N18 | 7743.67 | 9645.0499999999993 | 80.290000000000006 |
| PCIE_TX_CAP_N19 | 7709.83 | 9519.06 | 80.989999999999995 |
| PCIE_TX_CAP_N20 | 7520.01 | 9188.35 | 81.84 |
| PCIE_TX_CAP_N21 | 7457.03 | 9062.3700000000008 | 82.29 |
| PCIE_TX_CAP_N22 | 7352.37 | 8857.65 | 83.01 |
| PCIE_TX_CAP_N23 | 7254.19 | 8731.66 | 83.08 |
| PCIE_TX_CAP_N24 | 7069.27 | 8487.57 | 83.29 |
| PCIE_TX_CAP_N25 | 7008.78 | 8361.58 | 83.82 |
| PCIE_TX_CAP_N26 | 6806.05 | 7967.88 | 85.42 |
| PCIE_TX_CAP_N27 | 6748.7 | 7841.9 | 86.06 |
| PCIE_TX_CAP_N28 | 6540.9 | 7542.68 | 86.72 |
| PCIE_TX_CAP_N29 | 6520.02 | 7416.7 | 87.91 |
| PCIE_TX_CAP_N30 | 6379.73 | 7211.98 | 88.46 |
| PCIE_TX_CAP_N31 | 6329.62 | 7085.99 | 89.33 |
| PCIE_TX_CAP_N32 | 5997.92 | 6684.42 | 89.73 |
| PCIE_TX_CAP_N33 | 6027.4 | 6637.17 | 90.81 |
| PCIE_TX_CAP_N34 | 5946.02 | 6511.19 | 91.32 |
| PCIE_TX_CAP_N35 | 5943.76 | 6463.95 | 91.95 |
| PCIE_TX_CAP_N36 | 5905.01 | 6337.96 | 93.17 |
| PCIE_TX_CAP_N37 | 5949.51 | 6290.72 | 94.58 |
| PCIE_TX_CAP_N38 | 6414.02 | 7108.98 | 90.22 |
| PCIE_TX_CAP_N39 | 6434.99 | 7234.96 | 88.94 |
| PCIE_TX_CAP_N40 | 6370.8 | 7368.82 | 86.46 |
| PCIE_TX_CAP_N41 | 6423.64 | 7494.8 | 85.71 |
| PCIE_TX_CAP_N42 | 6409.96 | 7542.05 | 84.99 |
| PCIE_TX_CAP_N43 | 6468.14 | 7668.03 | 84.35 |
| PCIE_TX_CAP_N44 | 6457.41 | 7715.27 | 83.7 |
| PCIE_TX_CAP_N45 | 6515.95 | 7841.25 | 83.1 |
| PCIE_TX_CAP_N46 | 6504.05 | 7888.5 | 82.45 |
| PCIE_TX_CAP_N47 | 6581.84 | 8014.48 | 82.12 |
| PCIE_TX_CAP_N48 | 6665.84 | 8250.7099999999991 | 80.790000000000006 |
| PCIE_TX_CAP_N49 | 6652.62 | 8297.9500000000007 | 80.17 |
| PCIE_TX_CAP_N50 | 6707.13 | 8423.94 | 79.62 |
| PCIE_TX_CAP_N51 | 6698.32 | 8471.18 | 79.069999999999993 |
| PCIE_TX_CAP_N52 | 6815.77 | 8691.65 | 78.42 |
| PCIE_TX_CAP_N53 | 6822.61 | 8738.89 | 78.069999999999993 |
| PCIE_TX_CAP_N54 | 6937.64 | 8864.8799999999992 | 78.260000000000005 |
| PCIE_TX_CAP_N55 | 6909.65 | 8912.1200000000008 | 77.53 |
| PCIE_TX_CAP_N56 | 6965.94 | 8998.74 | 77.41 |
| PCIE_TX_CAP_N57 | 6972.05 | 9045.98 | 77.069999999999993 |
| PCIE_TX_CAP_N58 | 7048.35 | 9171.9699999999993 | 76.849999999999994 |
| PCIE_TX_CAP_N59 | 7046.47 | 9219.2099999999991 | 76.430000000000007 |
| PCIE_TX_CAP_N60 | 7800.63 | 10431.81 | 74.78 |
| PCIE_TX_CAP_N61 | 7784.61 | 10479.049999999999 | 74.290000000000006 |
| PCIE_TX_CAP_N62 | 7868.84 | 10605.04 | 74.2 |
| PCIE_TX_CAP_N63 | 7908.67 | 10652.28 | 74.239999999999995 |
| PCIE_TX_CAP_N64 | 8373.81 | 11148.35 | 75.11 |
| PCIE_TX_CAP_N65 | 8413.2900000000009 | 11274.33 | 74.62 |
| PCIE_TX_CAP_N66 | 8575.93 | 11479.06 | 74.709999999999994 |
| PCIE_TX_CAP_N67 | 8648.5300000000007 | 11605.04 | 74.52 |
| PCIE_TX_CAP_N68 | 8813.09 | 11809.77 | 74.63 |
| PCIE_TX_CAP_N69 | 9166.42 | 12187.72 | 75.209999999999994 |
| PCIE_TX_CAP_N70 | 9354.43 | 12392.44 | 75.489999999999995 |
| PCIE_TX_CAP_N71 | 9466.91 | 12518.43 | 75.62 |
| PCIE_TX_CAP_N72 | 9734.81 | 12857.01 | 75.72 |
| PCIE_TX_CAP_N73 | 9848.6299999999992 | 12982.99 | 75.86 |
| PCIE_TX_CAP_N74 | 10005.99 | 13187.72 | 75.87 |
| PCIE_TX_CAP_N75 | 10265.32 | 13313.7 | 77.099999999999994 |
| PCIE_TX_CAP_N76 | 10420.68 | 10974.82 | 94.95 |
| PCIE_TX_CAP_N78 | 520.16 | 531.16 | 97.93 |
| PCIE_TX_CAP_N80 | 3821.01 | 3714.72 | 102.86 |
| PCIE_TX_CAP_N81 | 3898.46 | 3805.98 | 102.43 |
| PCIE_TX_CAP_N82 | 3834.26 | 3720.98 | 103.04 |
| PCIE_TX_CAP_N83 | 3607.97 | 3472.24 | 103.91 |
| PCIE_TX_CAP_N84 | 3241.77 | 2957.34 | 109.62 |
| PCIE_TX_CAP_N85 | 3316.55 | 3066.5 | 108.15 |
| PCIE_TX_CAP_N86 | 3247.17 | 2963.6 | 109.57 |
| PCIE_TX_CAP_N87 | 3041.83 | 2722.86 | 111.71 |
| PCIE_TX_CAP_N88 | 2747.84 | 2420.81 | 113.51 |
| PCIE_TX_CAP_N89 | 2792.6 | 2682.79 | 104.09 |
| PCIE_TX_CAP_N90 | 2763.99 | 2579.5500000000002 | 107.15 |
| PCIE_TX_CAP_N91 | 1856.09 | 1755.49 | 105.73 |
| PCIE_TX_CAP_N92 | 2056.38 | 2124.23 | 96.81 |
| PCIE_TX_CAP_N93 | 2036.36 | 1954.23 | 104.2 |
| PCIE_TX_CAP_N94 | 2176.7399999999998 | 2122.9699999999998 | 102.53 |
| PCIE_TX_CAP_N95 | 2222.27 | 2272.9699999999998 | 97.77 |
| PCIE_TX_CAP_P0 | 1403.24 | 1547.46 | 90.68 |
| PCIE_TX_CAP_P1 | 1390.88 | 1512.46 | 91.96 |
| PCIE_TX_CAP_P2 | 1859.21 | 1354.78 | 137.22999999999999 |
| PCIE_TX_CAP_P3 | 2039.84 | 1439.04 | 141.75 |
| PCIE_TX_CAP_P4 | 2095.09 | 1639.65 | 127.78 |
| PCIE_TX_CAP_P5 | 2301.77 | 1763.18 | 130.55000000000001 |
| PCIE_TX_CAP_P6 | 2235.89 | 1850.13 | 120.85 |
| PCIE_TX_CAP_P7 | 2215.67 | 1856.56 | 119.34 |
| PCIE_TX_CAP_P8 | 2337.4899999999998 | 1904.54 | 122.73 |
| PCIE_TX_CAP_P9 | 2498.1 | 2156.48 | 115.84 |
| PCIE_TX_CAP_P10 | 2564.15 | 2245.06 | 114.21 |
| PCIE_TX_CAP_P11 | 2703.49 | 2411.83 | 112.09 |
| PCIE_TX_CAP_P12 | 2894.91 | 2603.08 | 111.21 |
| PCIE_TX_CAP_P13 | 3050.93 | 2836 | 107.58 |
| PCIE_TX_CAP_P14 | 3158.42 | 2929.7 | 107.81 |
| PCIE_TX_CAP_P15 | 3274.18 | 3104.21 | 105.48 |
| PCIE_TX_CAP_P16 | 7918.99 | 9975.1200000000008 | 79.39 |
| PCIE_TX_CAP_P17 | 7878.65 | 9849.14 | 79.989999999999995 |
| PCIE_TX_CAP_P18 | 7743.82 | 9644.42 | 80.290000000000006 |
| PCIE_TX_CAP_P19 | 7709.85 | 9518.43 | 81 |
| PCIE_TX_CAP_P20 | 7519.48 | 9187.7199999999993 | 81.84 |
| PCIE_TX_CAP_P21 | 7457 | 9061.74 | 82.29 |
| PCIE_TX_CAP_P22 | 7352.52 | 8857.02 | 83.01 |
| PCIE_TX_CAP_P23 | 7253.69 | 8731.0300000000007 | 83.08 |
| PCIE_TX_CAP_P24 | 7069.43 | 8486.94 | 83.3 |
| PCIE_TX_CAP_P25 | 7008.69 | 8360.9500000000007 | 83.83 |
| PCIE_TX_CAP_P26 | 6806.07 | 7967.25 | 85.43 |
| PCIE_TX_CAP_P27 | 6748.5 | 7841.27 | 86.06 |
| PCIE_TX_CAP_P28 | 6541.08 | 7542.05 | 86.73 |
| PCIE_TX_CAP_P29 | 6520.08 | 7416.07 | 87.92 |
| PCIE_TX_CAP_P30 | 6380.2 | 7211.35 | 88.47 |
| PCIE_TX_CAP_P31 | 6329.82 | 7085.36 | 89.34 |
| PCIE_TX_CAP_P32 | 5997.29 | 6683.79 | 89.73 |
| PCIE_TX_CAP_P33 | 6027.29 | 6636.54 | 90.82 |
| PCIE_TX_CAP_P34 | 5945.54 | 6510.56 | 91.32 |
| PCIE_TX_CAP_P35 | 5944.28 | 6463.32 | 91.97 |
| PCIE_TX_CAP_P36 | 5904.38 | 6337.33 | 93.17 |
| PCIE_TX_CAP_P37 | 5949.78 | 6290.09 | 94.59 |
| PCIE_TX_CAP_P38 | 6413.51 | 7188.35 | 89.22 |
| PCIE_TX_CAP_P39 | 6434.46 | 7314.33 | 87.97 |
| PCIE_TX_CAP_P40 | 6370.77 | 7448.19 | 85.53 |
| PCIE_TX_CAP_P41 | 6423.3 | 7574.17 | 84.81 |
| PCIE_TX_CAP_P42 | 6410.1 | 7621.42 | 84.11 |
| PCIE_TX_CAP_P43 | 6468.01 | 7747.4 | 83.49 |
| PCIE_TX_CAP_P44 | 6456.93 | 7794.64 | 82.84 |
| PCIE_TX_CAP_P45 | 6515.2 | 7920.62 | 82.26 |
| PCIE_TX_CAP_P46 | 6503.79 | 7967.87 | 81.63 |
| PCIE_TX_CAP_P47 | 6581.28 | 8093.85 | 81.31 |
| PCIE_TX_CAP_P48 | 6665.02 | 8330.08 | 80.010000000000005 |
| PCIE_TX_CAP_P49 | 6652.18 | 8377.32 | 79.41 |
| PCIE_TX_CAP_P50 | 6706.84 | 8503.31 | 78.87 |
| PCIE_TX_CAP_P51 | 6698.57 | 8550.5499999999993 | 78.34 |
| PCIE_TX_CAP_P52 | 6815.97 | 8771.02 | 77.709999999999994 |
| PCIE_TX_CAP_P53 | 6822.24 | 8818.26 | 77.36 |
| PCIE_TX_CAP_P54 | 6937.12 | 8944.25 | 77.56 |
| PCIE_TX_CAP_P55 | 6908.91 | 8991.49 | 76.84 |
| PCIE_TX_CAP_P56 | 6965.17 | 9078.11 | 76.72 |
| PCIE_TX_CAP_P57 | 6971.8 | 9125.35 | 76.400000000000006 |
| PCIE_TX_CAP_P58 | 7047.69 | 9251.34 | 76.180000000000007 |
| PCIE_TX_CAP_P59 | 7045.63 | 9298.58 | 75.77 |
| PCIE_TX_CAP_P60 | 7801.25 | 10511.18 | 74.22 |
| PCIE_TX_CAP_P61 | 7783.84 | 10558.42 | 73.72 |
| PCIE_TX_CAP_P62 | 7868.93 | 10684.41 | 73.650000000000006 |
| PCIE_TX_CAP_P63 | 7909.19 | 10731.65 | 73.7 |
| PCIE_TX_CAP_P64 | 8373.36 | 11227.72 | 74.58 |
| PCIE_TX_CAP_P65 | 8414.16 | 11353.7 | 74.11 |
| PCIE_TX_CAP_P66 | 8576.7000000000007 | 11558.43 | 74.2 |
| PCIE_TX_CAP_P67 | 8648.16 | 11684.41 | 74.010000000000005 |
| PCIE_TX_CAP_P68 | 8813.48 | 11889.14 | 74.13 |
| PCIE_TX_CAP_P69 | 9167.2999999999993 | 12267.09 | 74.73 |
| PCIE_TX_CAP_P70 | 9354.66 | 12471.81 | 75.010000000000005 |
| PCIE_TX_CAP_P71 | 9467 | 12597.8 | 75.150000000000006 |
| PCIE_TX_CAP_P72 | 9734.42 | 12936.38 | 75.25 |
| PCIE_TX_CAP_P73 | 9848 | 13062.36 | 75.39 |
| PCIE_TX_CAP_P74 | 10005.36 | 13267.09 | 75.41 |
| PCIE_TX_CAP_P75 | 10265.1 | 13393.07 | 76.64 |
| PCIE_TX_CAP_P76 | 10420.25 | 11049.19 | 94.31 |
| PCIE_TX_CAP_P78 | 520.32000000000005 | 605.04 | 86 |
| PCIE_TX_CAP_P80 | 3821.14 | 3789.09 | 100.85 |
| PCIE_TX_CAP_P81 | 3898.16 | 3880.35 | 100.46 |
| PCIE_TX_CAP_P82 | 3834.85 | 3795.35 | 101.04 |
| PCIE_TX_CAP_P83 | 3607.77 | 3546.61 | 101.72 |
| PCIE_TX_CAP_P84 | 3241.19 | 3031.71 | 106.91 |
| PCIE_TX_CAP_P85 | 3316.87 | 3140.17 | 105.63 |
| PCIE_TX_CAP_P86 | 3246.61 | 3037.97 | 106.87 |
| PCIE_TX_CAP_P87 | 3041.65 | 2797.23 | 108.74 |
| PCIE_TX_CAP_P88 | 2747.08 | 2416.44 | 113.68 |
| PCIE_TX_CAP_P89 | 2792.88 | 2678.42 | 104.27 |
| PCIE_TX_CAP_P90 | 2763.98 | 2575.1799999999998 | 107.33 |
| PCIE_TX_CAP_P91 | 1856.47 | 1759.86 | 105.49 |
| PCIE_TX_CAP_P92 | 2056.69 | 2128.6 | 96.62 |
| PCIE_TX_CAP_P93 | 2036.01 | 1958.6 | 103.95 |
| PCIE_TX_CAP_P94 | 2176.23 | 2127.34 | 102.3 |
| PCIE_TX_CAP_P95 | 2222.3000000000002 | 2277.34 | 97.58 |
| PCIE_TX_N0 | 718.19 | 873.26 | 82.24 |
| PCIE_TX_N1 | 1042.57 | 917.87 | 113.59 |
| PCIE_TX_N2 | 477.87 | 566.20000000000005 | 84.4 |
| PCIE_TX_N3 | 592.85 | 561.80999999999995 | 105.53 |
| PCIE_TX_N4 | 662.13 | 718.76 | 92.12 |
| PCIE_TX_N5 | 375.87 | 366.94 | 102.43 |
| PCIE_TX_N6 | 374.9 | 365.3 | 102.63 |
| PCIE_TX_N7 | 542.96 | 600.08000000000004 | 90.48 |
| PCIE_TX_N8 | 648.04999999999995 | 679.18 | 95.42 |
| PCIE_TX_N9 | 375.04 | 366.55 | 102.32 |
| PCIE_TX_N10 | 374.64 | 366.61 | 102.19 |
| PCIE_TX_N11 | 543.38 | 602.01 | 90.26 |
| PCIE_TX_N12 | 669.56 | 571.19000000000005 | 117.22 |
| PCIE_TX_N13 | 389.95 | 449.78 | 86.7 |
| PCIE_TX_N14 | 404.64 | 453.06 | 89.31 |
| PCIE_TX_N15 | 578.99 | 696.38 | 83.14 |
| PCIE_TX_N16 | 505.21 | 503.44 | 100.35 |
| PCIE_TX_N17 | 505.21 | 503.44 | 100.35 |
| PCIE_TX_N18 | 505.21 | 503.44 | 100.35 |
| PCIE_TX_N19 | 505.21 | 503.44 | 100.35 |
| PCIE_TX_N20 | 505.21 | 503.44 | 100.35 |
| PCIE_TX_N21 | 505.21 | 503.44 | 100.35 |
| PCIE_TX_N22 | 505.21 | 503.44 | 100.35 |
| PCIE_TX_N23 | 505.21 | 503.44 | 100.35 |
| PCIE_TX_N24 | 505.21 | 503.44 | 100.35 |
| PCIE_TX_N25 | 505.21 | 503.44 | 100.35 |
| PCIE_TX_N26 | 505.21 | 503.44 | 100.35 |
| PCIE_TX_N27 | 505.21 | 503.44 | 100.35 |
| PCIE_TX_N28 | 505.21 | 503.44 | 100.35 |
| PCIE_TX_N29 | 505.21 | 503.44 | 100.35 |
| PCIE_TX_N30 | 505.21 | 503.44 | 100.35 |
| PCIE_TX_N31 | 505.21 | 503.44 | 100.35 |
| PCIE_TX_N32 | 505.21 | 503.44 | 100.35 |
| PCIE_TX_N33 | 505.21 | 503.44 | 100.35 |
| PCIE_TX_N34 | 505.21 | 503.44 | 100.35 |
| PCIE_TX_N35 | 505.21 | 503.44 | 100.35 |
| PCIE_TX_N36 | 505.21 | 503.44 | 100.35 |
| PCIE_TX_N37 | 505.21 | 503.44 | 100.35 |
| PCIE_TX_N38 | 505.21 | 503.44 | 100.35 |
| PCIE_TX_N39 | 505.21 | 503.44 | 100.35 |
| PCIE_TX_N40 | 505.21 | 503.44 | 100.35 |
| PCIE_TX_N41 | 505.21 | 503.44 | 100.35 |
| PCIE_TX_N42 | 505.21 | 503.44 | 100.35 |
| PCIE_TX_N43 | 505.21 | 503.44 | 100.35 |
| PCIE_TX_N44 | 505.21 | 503.44 | 100.35 |
| PCIE_TX_N45 | 505.21 | 503.45 | 100.35 |
| PCIE_TX_N46 | 505.21 | 503.44 | 100.35 |
| PCIE_TX_N47 | 505.21 | 503.45 | 100.35 |
| PCIE_TX_N48 | 505.21 | 503.44 | 100.35 |
| PCIE_TX_N49 | 505.21 | 503.44 | 100.35 |
| PCIE_TX_N50 | 505.21 | 503.44 | 100.35 |
| PCIE_TX_N51 | 505.21 | 503.44 | 100.35 |
| PCIE_TX_N52 | 505.21 | 503.44 | 100.35 |
| PCIE_TX_N53 | 505.21 | 503.45 | 100.35 |
| PCIE_TX_N54 | 505.21 | 503.44 | 100.35 |
| PCIE_TX_N55 | 505.21 | 503.45 | 100.35 |
| PCIE_TX_N56 | 505.21 | 503.44 | 100.35 |
| PCIE_TX_N57 | 505.21 | 503.44 | 100.35 |
| PCIE_TX_N58 | 505.21 | 503.44 | 100.35 |
| PCIE_TX_N59 | 505.21 | 503.44 | 100.35 |
| PCIE_TX_N60 | 505.21 | 503.44 | 100.35 |
| PCIE_TX_N61 | 505.21 | 503.45 | 100.35 |
| PCIE_TX_N62 | 505.21 | 503.44 | 100.35 |
| PCIE_TX_N63 | 505.21 | 503.45 | 100.35 |
| PCIE_TX_N64 | 505.21 | 503.44 | 100.35 |
| PCIE_TX_N65 | 505.21 | 503.44 | 100.35 |
| PCIE_TX_N66 | 505.21 | 503.44 | 100.35 |
| PCIE_TX_N67 | 505.21 | 503.44 | 100.35 |
| PCIE_TX_N68 | 505.21 | 503.44 | 100.35 |
| PCIE_TX_N69 | 505.21 | 503.44 | 100.35 |
| PCIE_TX_N70 | 505.21 | 503.44 | 100.35 |
| PCIE_TX_N71 | 505.21 | 503.44 | 100.35 |
| PCIE_TX_N72 | 505.21 | 503.44 | 100.35 |
| PCIE_TX_N73 | 505.21 | 503.44 | 100.35 |
| PCIE_TX_N74 | 505.21 | 503.44 | 100.35 |
| PCIE_TX_N75 | 505.21 | 503.44 | 100.35 |
| PCIE_TX_N76 | 327.33 | 361.06 | 90.66 |
| PCIE_TX_N78 | 9066.85 | 9144.09 | 99.16 |
| PCIE_TX_N80 | 661.48 | 515.46 | 128.33000000000001 |
| PCIE_TX_N81 | 444.19 | 526.09 | 84.43 |
| PCIE_TX_N82 | 445.28 | 529.67999999999995 | 84.07 |
| PCIE_TX_N83 | 630.08000000000004 | 511.87 | 123.09 |
| PCIE_TX_N84 | 602.87 | 682.29 | 88.36 |
| PCIE_TX_N85 | 386.08 | 375.56 | 102.8 |
| PCIE_TX_N86 | 379.81 | 361.65 | 105.02 |
| PCIE_TX_N87 | 578.54999999999995 | 670.7 | 86.26 |
| PCIE_TX_N88 | 632.55999999999995 | 744.21 | 85 |
| PCIE_TX_N89 | 378.06 | 411.36 | 91.9 |
| PCIE_TX_N90 | 400.47 | 426.02 | 94 |
| PCIE_TX_N91 | 1081.75 | 1165.6300000000001 | 92.8 |
| PCIE_TX_N92 | 555.75 | 531.14 | 104.63 |
| PCIE_TX_N93 | 641.12 | 551.53 | 116.24 |
| PCIE_TX_N94 | 445.95 | 397.21 | 112.27 |
| PCIE_TX_N95 | 455.55 | 397.6 | 114.58 |
| PCIE_TX_P0 | 718.83 | 863.86 | 83.21 |
| PCIE_TX_P1 | 1043.31 | 978.47 | 106.63 |
| PCIE_TX_P2 | 477.06 | 446.55 | 106.83 |
| PCIE_TX_P3 | 592.85 | 512.16 | 115.75 |
| PCIE_TX_P4 | 662.81 | 669.12 | 99.06 |
| PCIE_TX_P5 | 375.94 | 306.7 | 122.58 |
| PCIE_TX_P6 | 374.79 | 306.75 | 122.18 |
| PCIE_TX_P7 | 542.92999999999995 | 539.49 | 100.64 |
| PCIE_TX_P8 | 648.27 | 629.53 | 102.98 |
| PCIE_TX_P9 | 374.13 | 306.72000000000003 | 121.98 |
| PCIE_TX_P10 | 374.94 | 306.72000000000003 | 122.24 |
| PCIE_TX_P11 | 543.41999999999996 | 541.41999999999996 | 100.37 |
| PCIE_TX_P12 | 669.04 | 521.54 | 128.28 |
| PCIE_TX_P13 | 389.31 | 389.19 | 100.03 |
| PCIE_TX_P14 | 404.78 | 392.47 | 103.14 |
| PCIE_TX_P15 | 579.05999999999995 | 635.79 | 91.08 |
| PCIE_TX_P16 | 505.2 | 503.45 | 100.35 |
| PCIE_TX_P17 | 505.21 | 503.44 | 100.35 |
| PCIE_TX_P18 | 505.21 | 503.44 | 100.35 |
| PCIE_TX_P19 | 505.22 | 503.45 | 100.35 |
| PCIE_TX_P20 | 505.2 | 503.45 | 100.35 |
| PCIE_TX_P21 | 505.21 | 503.44 | 100.35 |
| PCIE_TX_P22 | 505.21 | 503.44 | 100.35 |
| PCIE_TX_P23 | 505.22 | 503.44 | 100.35 |
| PCIE_TX_P24 | 505.21 | 503.44 | 100.35 |
| PCIE_TX_P25 | 505.22 | 503.45 | 100.35 |
| PCIE_TX_P26 | 505.2 | 503.45 | 100.35 |
| PCIE_TX_P27 | 505.21 | 503.44 | 100.35 |
| PCIE_TX_P28 | 505.2 | 503.45 | 100.35 |
| PCIE_TX_P29 | 505.21 | 503.44 | 100.35 |
| PCIE_TX_P30 | 505.21 | 503.44 | 100.35 |
| PCIE_TX_P31 | 505.2 | 503.45 | 100.35 |
| PCIE_TX_P32 | 505.21 | 503.44 | 100.35 |
| PCIE_TX_P33 | 505.2 | 503.45 | 100.35 |
| PCIE_TX_P34 | 505.21 | 503.44 | 100.35 |
| PCIE_TX_P35 | 505.21 | 503.44 | 100.35 |
| PCIE_TX_P36 | 505.21 | 503.44 | 100.35 |
| PCIE_TX_P37 | 505.21 | 503.44 | 100.35 |
| PCIE_TX_P38 | 505.2 | 503.45 | 100.35 |
| PCIE_TX_P39 | 505.21 | 503.44 | 100.35 |
| PCIE_TX_P40 | 505.21 | 503.45 | 100.35 |
| PCIE_TX_P41 | 505.21 | 503.44 | 100.35 |
| PCIE_TX_P42 | 505.2 | 503.45 | 100.35 |
| PCIE_TX_P43 | 505.21 | 503.44 | 100.35 |
| PCIE_TX_P44 | 505.21 | 503.44 | 100.35 |
| PCIE_TX_P45 | 505.2 | 503.43 | 100.35 |
| PCIE_TX_P46 | 505.21 | 503.44 | 100.35 |
| PCIE_TX_P47 | 505.2 | 503.44 | 100.35 |
| PCIE_TX_P48 | 505.2 | 503.45 | 100.35 |
| PCIE_TX_P49 | 505.21 | 503.44 | 100.35 |
| PCIE_TX_P50 | 505.2 | 503.45 | 100.35 |
| PCIE_TX_P51 | 505.21 | 503.44 | 100.35 |
| PCIE_TX_P52 | 505.21 | 503.44 | 100.35 |
| PCIE_TX_P53 | 505.21 | 503.44 | 100.35 |
| PCIE_TX_P54 | 505.21 | 503.44 | 100.35 |
| PCIE_TX_P55 | 505.21 | 503.44 | 100.35 |
| PCIE_TX_P56 | 505.21 | 503.44 | 100.35 |
| PCIE_TX_P57 | 505.21 | 503.44 | 100.35 |
| PCIE_TX_P58 | 505.22 | 503.44 | 100.35 |
| PCIE_TX_P59 | 505.21 | 503.44 | 100.35 |
| PCIE_TX_P60 | 505.21 | 503.44 | 100.35 |
| PCIE_TX_P61 | 505.21 | 503.44 | 100.35 |
| PCIE_TX_P62 | 505.21 | 503.44 | 100.35 |
| PCIE_TX_P63 | 505.21 | 503.44 | 100.35 |
| PCIE_TX_P64 | 505.2 | 503.45 | 100.35 |
| PCIE_TX_P65 | 505.21 | 503.44 | 100.35 |
| PCIE_TX_P66 | 505.2 | 503.45 | 100.35 |
| PCIE_TX_P67 | 505.21 | 503.44 | 100.35 |
| PCIE_TX_P68 | 505.2 | 503.45 | 100.35 |
| PCIE_TX_P69 | 505.2 | 503.45 | 100.35 |
| PCIE_TX_P70 | 505.21 | 503.44 | 100.35 |
| PCIE_TX_P71 | 505.2 | 503.45 | 100.35 |
| PCIE_TX_P72 | 505.21 | 503.44 | 100.35 |
| PCIE_TX_P73 | 505.21 | 503.44 | 100.35 |
| PCIE_TX_P74 | 505.2 | 503.45 | 100.35 |
| PCIE_TX_P75 | 505.21 | 503.44 | 100.35 |
| PCIE_TX_P76 | 327.38 | 357.56 | 91.56 |
| PCIE_TX_P78 | 9067.34 | 9198.2900000000009 | 98.58 |
| PCIE_TX_P80 | 661.63 | 456.06 | 145.08000000000001 |
| PCIE_TX_P81 | 444.61 | 476.45 | 93.32 |
| PCIE_TX_P82 | 444.51 | 480.03 | 92.6 |
| PCIE_TX_P83 | 629.87 | 459.64 | 137.04 |
| PCIE_TX_P84 | 603.11 | 621.69000000000005 | 97.01 |
| PCIE_TX_P85 | 386.29 | 325.22000000000003 | 118.78 |
| PCIE_TX_P86 | 379.5 | 312 | 121.63 |
| PCIE_TX_P87 | 578.9 | 610.11 | 94.89 |
| PCIE_TX_P88 | 633.04 | 683.62 | 92.6 |
| PCIE_TX_P89 | 378.18 | 350.77 | 107.81 |
| PCIE_TX_P90 | 400.32 | 365.43 | 109.55 |
| PCIE_TX_P91 | 1081.56 | 1175.04 | 92.04 |
| PCIE_TX_P92 | 555.48 | 540.54999999999995 | 102.76 |
| PCIE_TX_P93 | 640.89 | 560.94000000000005 | 114.25 |
| PCIE_TX_P94 | 445.95 | 446.86 | 99.8 |
| PCIE_TX_P95 | 455.19 | 447.25 | 101.78 |
| PD_USB2VRES | 390.13 | 505.06 | 77.25 |
| PD_ZQ | 255.39 | 241.25 | 105.86 |
| PE1_PERST# | 17150.55 | 16421.060000000001 | 104.44 |
| PE1_PERST#_BMC | 756.3 | 504.46 | 149.91999999999999 |
| PE1_PERST#_R | 327.76 | 167.37 | 195.83 |
| PECI0_R | 420.36 | 507.07 | 82.9 |
| PEER_BMC_HB | 4757.79 | 3774.4 | 126.05 |
| PEER_TRAY_BMC | 384.15 | 390.06 | 98.48 |
| PEER_TRAY_R | 5628.05 | 4675.7 | 120.37 |
| PEWAKE# | 14252.02 | 12726.48 | 111.99 |
| PHY_RESET_N | 1298.26 | 906.3 | 143.25 |
| PHY_WAKE_N | 290.32 | 348.01 | 83.42 |
| PM8536_HB | 1047.6099999999999 | 920.68 | 113.79 |
| PM8536_PG2_R | 132.1 | 106.25 | 124.33 |
| PM8536_RST# | 3730.78 | 3690.9 | 101.08 |
| PM8536_RST#_AND | 202.67 | 127.92 | 158.43 |
| PM8536_RST#_LS | 5171.33 | 4312.21 | 119.92 |
| PM8536_RST#_LS_R | 246.27 | 174 | 141.54 |
| PMC_PLX_BOARD | 293.95 | 245.53 | 119.72 |
| PMC_R_RXD5 | 173.43 | 137.05000000000001 | 126.55 |
| PMC_R_TXD5 | 145.91999999999999 | 161.05000000000001 | 90.6 |
| PQ21_G | 125.27 | 65.05 | 192.58 |
| PQ22_G | 2212.84 | 1734.28 | 127.59 |
| PU_IBMC_BT_HOLD_N | 110.86 | 120.64 | 91.9 |
| PWGD_P0V9_E_PG_R | 314.43 | 358.55 | 87.69 |
| PWM_EXP_A | 5426.97 | 4433.03 | 122.42 |
| PWRGD_P1V26_STBY | 9848.23 | 9985.0499999999993 | 98.63 |
| PWRGD_P1V538_STBY | 5472.55 | 4639.5 | 117.96 |
| PWRGD_P1V8_STBY | 13999.02 | 13801 | 101.43 |
| Q20_G | 295.64999999999998 | 279.48 | 105.79 |
| Q21_G | 118.83 | 132.87 | 89.43 |
| Q22_D | 2254.0500000000002 | 1586.31 | 142.09 |
| Q22_G | 129.36000000000001 | 135.80000000000001 | 95.26 |
| Q3202_D | 291.64 | 240.88 | 121.07 |
| Q3203_G | 0 | 135.5 | 0 |
| Q37_G | 123.38 | 80.75 | 152.79 |
| Q40_D | 386.08 | 359.51 | 107.39 |
| Q42_D | 211.53 | 153.56 | 137.75 |
| Q43_B | 128.94 | 92.04 | 140.09 |
| Q43_C | 284.81 | 223.99 | 127.15 |
| Q45_D | 428.41 | 164.79 | 259.97000000000003 |
| Q46_D | 177.27 | 101.49 | 174.66 |
| Q46_G | 160.1 | 96.44 | 166.01 |
| Q95_D | 594.47 | 490 | 121.32 |
| Q95_G | 207.45 | 152.25 | 136.26 |
| RMII0_BMC_C_CRS_DV | 282.41000000000003 | 280.06 | 100.84 |
| RMII0_BMC_C_PHY_TXD0 | 293.58 | 286.42 | 102.5 |
| RMII0_BMC_C_PHY_TXD1 | 332.89 | 357.92 | 93.01 |
| RMII0_BMC_C_TX_EN | 213.83 | 216.43 | 98.8 |
| RMII0_PHY_BMC_RXCTL0 | 836.62 | 781.38 | 107.07 |
| RMII_BMC_CRS_DV | 2437.88 | 2315.9299999999998 | 105.27 |
| RMII_BMC_PHY_TXD0 | 2020.56 | 2177.4899999999998 | 92.79 |
| RMII_BMC_PHY_TXD1 | 2042.05 | 2134.17 | 95.68 |
| RMII_BMC_RX_ER | 877.74 | 864.95 | 101.48 |
| RMII_BMC_TX_EN | 3121.84 | 2526.06 | 123.59 |
| RMII_CRS_DV | 94.89 | 78.349999999999994 | 121.12 |
| RMII_PHY_BMC_RXD0 | 2262.06 | 2398.92 | 94.3 |
| RMII_PHY_BMC_RXD1 | 2259.6999999999998 | 2489.15 | 90.78 |
| RMII_PHY_BMC_RXD0_R | 135.16999999999999 | 137.54 | 98.28 |
| RMII_PHY_BMC_RXD1_R | 122.66 | 119.43 | 102.71 |
| RMII_REF_CLK | 55.48 | 39.78 | 139.46 |
| RMII_RXD_0 | 55.57 | 39.54 | 140.55000000000001 |
| RMII_RXD_1 | 55.66 | 0 | 1.#J |
| RMII_RX_ER | 95.23 | 79.03 | 120.5 |
| RMII_TXD_0 | 56.08 | 39.770000000000003 | 141.01 |
| RMII_TXD_1 | 55.57 | 0.4 | 13892.12 |
| RMII_TX_EN | 55.81 | 39.42 | 141.57 |
| ROMA0 | 7289.22 | 5404.97 | 134.86000000000001 |
| ROMA1 | 290.63 | 261.04000000000002 | 111.34 |
| ROMA2 | 250.36 | 234.42 | 106.8 |
| ROMA3 | 399.9 | 374.33 | 106.83 |
| ROMA4 | 342.54 | 344.15 | 99.53 |
| ROMA5 | 429.15 | 420.91 | 101.96 |
| ROMA6 | 275.33999999999997 | 274.42 | 100.34 |
| ROMA7 | 476.93 | 437.04 | 109.13 |
| ROMA8 | 497.41 | 469.42 | 105.96 |
| ROMA9 | 482.45 | 517.91999999999996 | 93.15 |
| ROMA10 | 402.1 | 392.84 | 102.36 |
| ROMA11 | 358.68 | 395.18 | 90.76 |
| ROMA12 | 431.1 | 501.71 | 85.93 |
| ROMA13 | 368.77 | 430.21 | 85.72 |
| ROMA14 | 317.02 | 358.71 | 88.38 |
| ROMA15 | 406.47 | 435.18 | 93.4 |
| ROMA16 | 403.94 | 351.34 | 114.97 |
| ROMA17 | 564.20000000000005 | 492.41 | 114.58 |
| ROMA18 | 382.89 | 352.65 | 108.58 |
| ROMA19 | 760.14 | 595.91999999999996 | 127.56 |
| ROMA20 | 374.97 | 352.83 | 106.28 |
| ROMA21 | 464.63 | 509.41 | 91.21 |
| ROMA22 | 240.17 | 273.43 | 87.83 |
| ROMA23 | 767.54 | 603.01 | 127.28 |
| ROMD0 | 359.91 | 393.05 | 91.57 |
| ROMD1 | 402.42 | 464.55 | 86.62 |
| ROMD2 | 5475.51 | 4629.38 | 118.28 |
| ROMD3 | 243.71 | 217.41 | 112.1 |
| ROMD4 | 285.14 | 278.05 | 102.55 |
| ROMD5 | 378.98 | 483.15 | 78.44 |
| ROMD6 | 247.63 | 255.06 | 97.09 |
| ROMD7 | 355.61 | 460.15 | 77.28 |
| ROMD0_R | 5747.16 | 5596.05 | 102.7 |
| ROMD1_R | 5835.02 | 5585.05 | 104.48 |
| ROMD2_R | 4375.1400000000003 | 4151.26 | 105.39 |
| ROMD2_SEC | 117.82 | 118.6 | 99.34 |
| RS232_UCTSB0 | 55.67 | 39.369999999999997 | 141.41 |
| RS232_URTSB0 | 55.66 | 0 | 1.#J |
| RST_BMC_DDR3_R_N | 147.61000000000001 | 79.290000000000006 | 186.17 |
| RST_BMC_EXTRST_N | 3647.17 | 2302.2199999999998 | 158.41999999999999 |
| RST_BMC_EXTRST_N_R | 935.11 | 1150.1600000000001 | 81.3 |
| RST_BTN# | 5164.05 | 4840.7700000000004 | 106.68 |
| RST_BTN#_R | 149.84 | 119.03 | 125.88 |
| RTC_CLK_OUT | 121.26 | 121.52 | 99.79 |
| RTC_I2C_SCL | 110.5 | 96.5 | 114.51 |
| RTC_I2C_SDA | 110.5 | 96.5 | 114.51 |
| RTC_INT_N | 182.15 | 149 | 122.25 |
| RTC_OSCI | 206.98 | 231 | 89.6 |
| RTC_OSCO | 206.98 | 231 | 89.6 |
| SAS_SMART_R_RX | 141.72 | 81.66 | 173.55 |
| SAS_SMART_R_TX | 166.93 | 81.84 | 203.97 |
| SEC_RST_N_R | 177.47 | 219.57 | 80.83 |
| SEC_SPI_HOLD_N | 105.04 | 100.48 | 104.53 |
| SHUTDOWN_RELEASE | 14441.22 | 9921.14 | 145.56 |
| SLED29_A | 2184.35 | 1573.31 | 138.84 |
| SLIDE_SW_PMC_RST# | 4976.99 | 4958.01 | 100.38 |
| SMART_UART_EN | 134.38999999999999 | 126.64 | 106.12 |
| SPICK | 1534.21 | 1403.34 | 109.33 |
| SPICK_R | 358.38 | 445.94 | 80.37 |
| SPICS0_N | 1266.9000000000001 | 1160.29 | 109.19 |
| SPICS0_N_R | 307.52 | 308.97000000000003 | 99.53 |
| SPIDI | 1579.93 | 1420.04 | 111.26 |
| SPIDI_R | 546.09 | 688.54 | 79.31 |
| SPIDO | 1557.93 | 1107.03 | 140.72999999999999 |
| SPIDO_R | 320.79000000000002 | 412.45 | 77.78 |
| SPI_CLK0 | 5076.8900000000003 | 5239.99 | 96.89 |
| SPI_CLK0_R | 180.95 | 202.26 | 89.46 |
| SPI_CSB0_0 | 4758.91 | 4857.33 | 97.97 |
| SPI_CSB0_1 | 56.28 | 3.49 | 1612.68 |
| SPI_DATA0_0 | 4936.5200000000004 | 4998.88 | 98.75 |
| SPI_DATA0_1 | 4488.76 | 4685.04 | 95.81 |
| SPI_DATA0_2 | 4567.6099999999997 | 4682.92 | 97.54 |
| SPI_DATA0_3 | 5118.51 | 5367.4 | 95.36 |
| SPI_DATA0_0_R | 319.86 | 239.81 | 133.38 |
| SPI_DATA0_1_R | 189.54 | 199.4 | 95.05 |
| SPI_DATA0_2_R | 188.21 | 198.4 | 94.86 |
| SPI_DATA0_3_R | 234.43 | 213.03 | 110.05 |
| SPI_FLASH_SELECT | 1313.94 | 1128 | 116.48 |
| SPI_FLASH_SELECT_R | 167.13 | 158.72 | 105.3 |
| SSD_ATNLED#0 | 283.11 | 138.1 | 205 |
| SSD_ATNLED#1 | 251.02 | 138.1 | 181.77 |
| SSD_ATNLED#2 | 263.74 | 225.42 | 117 |
| SSD_ATNLED#3 | 240.07 | 143.1 | 167.76 |
| SSD_ATNLED#4 | 238.43 | 138.1 | 172.65 |
| SSD_ATNLED#5 | 260.12 | 164.13 | 158.47999999999999 |
| SSD_ATNLED#6 | 284.74 | 231.3 | 123.1 |
| SSD_ATNLED#7 | 244.25 | 169.95 | 143.72 |
| SSD_ATNLED#8 | 265.23 | 201.5 | 131.63 |
| SSD_ATNLED#9 | 254.47 | 162.5 | 156.6 |
| SSD_ATNLED#10 | 291.3 | 281.3 | 103.55 |
| SSD_ATNLED#11 | 218.43 | 129.94999999999999 | 168.09 |
| SSD_ATNLED#12 | 212.53 | 191.3 | 111.1 |
| SSD_ATNLED#13 | 244.72 | 155.15 | 157.72999999999999 |
| SSD_ATNLED#14 | 215.96 | 141.30000000000001 | 152.84 |
| SSD_ATNLED#0_R | 2238.35 | 2133.89 | 104.9 |
| SSD_ATNLED#10_R | 1572.11 | 1763.89 | 89.13 |
| SSD_ATNLED#11_R | 6744.1 | 4620.55 | 145.96 |
| SSD_ATNLED#12_R | 1548.75 | 1634.36 | 94.76 |
| SSD_ATNLED#13_R | 7366.77 | 3735.94 | 197.19 |
| SSD_ATNLED#14_R | 2055.08 | 1788.75 | 114.89 |
| SSD_ATNLED#1_R | 3639.84 | 2394.56 | 152 |
| SSD_ATNLED#2_R | 2280.54 | 2464.79 | 92.52 |
| SSD_ATNLED#3_R | 1951.68 | 1831.37 | 106.57 |
| SSD_ATNLED#4_R | 3175.28 | 3528.58 | 89.99 |
| SSD_ATNLED#5_R | 2550.9299999999998 | 2245.9 | 113.58 |
| SSD_ATNLED#6_R | 688.39 | 707.43 | 97.31 |
| SSD_ATNLED#7_R | 3364.33 | 2571.9699999999998 | 130.81 |
| SSD_ATNLED#8_R | 5434.55 | 3188.02 | 170.47 |
| SSD_ATNLED#9_R | 2610.3000000000002 | 2445.2399999999998 | 106.75 |
| SSD_PERST#0 | 705.64 | 428.53 | 164.67 |
| SSD_PERST#1 | 687.66 | 442.53 | 155.38999999999999 |
| SSD_PERST#2 | 894.01 | 557.57000000000005 | 160.34 |
| SSD_PERST#3 | 735.36 | 519.24 | 141.62 |
| SSD_PERST#4 | 670.92 | 556 | 120.67 |
| SSD_PERST#5 | 767.37 | 559.61 | 137.13 |
| SSD_PERST#6 | 502.09 | 509.8 | 98.49 |
| SSD_PERST#7 | 492.98 | 279.36 | 176.47 |
| SSD_PERST#8 | 749.98 | 565 | 132.74 |
| SSD_PERST#9 | 806.86 | 498 | 162.02000000000001 |
| SSD_PERST#10 | 515.03 | 547.01 | 94.15 |
| SSD_PERST#11 | 523.30999999999995 | 311.36 | 168.07 |
| SSD_PERST#12 | 497.81 | 479.01 | 103.92 |
| SSD_PERST#13 | 676.95 | 502.54 | 134.71 |
| SSD_PERST#14 | 486.61 | 416.27 | 116.9 |
| SSD_PERST#0_B0 | 148.25 | 76.09 | 194.84 |
| SSD_PERST#0_B1 | 143.61000000000001 | 76.09 | 188.74 |
| SSD_PERST#0_B2 | 119.92 | 91.09 | 131.65 |
| SSD_PERST#0_B3 | 112.44 | 128.19999999999999 | 87.71 |
| SSD_PERST#0_B4 | 148.4 | 76.09 | 195.03 |
| SSD_PERST#0_B5 | 120.53 | 91.09 | 132.32 |
| SSD_PERST#0_B6 | 187.08 | 76.09 | 245.87 |
| SSD_PERST#0_B7 | 185.34 | 98.09 | 188.95 |
| SSD_PERST#0_B8 | 171.51 | 152 | 112.83 |
| SSD_PERST#0_B9 | 177.09 | 91.09 | 194.41 |
| SSD_PERST#0_B10 | 117.5 | 76.09 | 154.43 |
| SSD_PERST#0_B11 | 100.3 | 103.09 | 97.29 |
| SSD_PERST#0_B12 | 142.4 | 76.09 | 187.14 |
| SSD_PERST#0_B13 | 127.03 | 110.33 | 115.13 |
| SSD_PERST#0_B14 | 267.33999999999997 | 76.09 | 351.34 |
| SSD_PERST#0_R | 2683.92 | 1782.47 | 150.57 |
| SSD_PERST#10_R | 2875.56 | 3036.33 | 94.71 |
| SSD_PERST#11_R | 10007.530000000001 | 7352.4 | 136.11000000000001 |
| SSD_PERST#12_R | 2167.7399999999998 | 1985.29 | 109.19 |
| SSD_PERST#13_R | 8148.15 | 4722.3900000000003 | 172.54 |
| SSD_PERST#14_R | 4114.16 | 3253.53 | 126.45 |
| SSD_PERST#1_R | 4081.87 | 3167.47 | 128.87 |
| SSD_PERST#2_R | 10065.620000000001 | 4478.53 | 224.75 |
| SSD_PERST#3_R | 2271.36 | 1848.38 | 122.88 |
| SSD_PERST#4_R | 3222.77 | 3167.64 | 101.74 |
| SSD_PERST#5_R | 3183.27 | 3107.24 | 102.45 |
| SSD_PERST#6_R | 1501.88 | 1363.33 | 110.16 |
| SSD_PERST#7_R | 4359.46 | 3377.24 | 129.08000000000001 |
| SSD_PERST#8_R | 5456.23 | 3269.09 | 166.9 |
| SSD_PERST#9_R | 4074.25 | 3470.12 | 117.41 |
| SSD_PERST_Y0 | 110.15 | 71.87 | 153.26 |
| SSD_PERST_Y1 | 120.58 | 84.4 | 142.86000000000001 |
| SSD_PERST_Y2 | 110.15 | 71.87 | 153.26 |
| SSD_PERST_Y3 | 113.64 | 78.599999999999994 | 144.58000000000001 |
| SSD_PERST_Y4 | 135.59 | 66.87 | 202.77 |
| SSD_PERST_Y5 | 115.4 | 71.87 | 160.57 |
| SSD_PERST_Y6 | 154.47 | 71.87 | 214.94 |
| SSD_PERST_Y7 | 142.44 | 71.87 | 198.19 |
| SSD_PERST_Y8 | 149.78 | 66.48 | 225.29 |
| SSD_PERST_Y9 | 134.12 | 71.87 | 186.62 |
| SSD_PERST_Y10 | 135.69 | 71.87 | 188.8 |
| SSD_PERST_Y11 | 140.77000000000001 | 66.84 | 210.61 |
| SSD_PERST_Y12 | 122.81 | 83.6 | 146.9 |
| SSD_PERST_Y13 | 119.88 | 76.87 | 155.96 |
| SSD_PERST_Y14 | 158.82 | 71.87 | 220.98 |
| SSD_PRSNT#0 | 228.29 | 152.5 | 149.69999999999999 |
| SSD_PRSNT#1 | 227.03 | 152.5 | 148.87 |
| SSD_PRSNT#2 | 210.44 | 209.02 | 100.68 |
| SSD_PRSNT#3 | 239.16 | 157.5 | 151.85 |
| SSD_PRSNT#4 | 268.72000000000003 | 152.5 | 176.21 |
| SSD_PRSNT#5 | 230.58 | 149.72999999999999 | 154 |
| SSD_PRSNT#6 | 277.51 | 245.7 | 112.95 |
| SSD_PRSNT#7 | 179.99 | 185.35 | 97.11 |
| SSD_PRSNT#8 | 242.91 | 187.1 | 129.83000000000001 |
| SSD_PRSNT#9 | 297.83 | 148.1 | 201.1 |
| SSD_PRSNT#10 | 395.97 | 295.7 | 133.91 |
| SSD_PRSNT#11 | 159.54 | 147.88999999999999 | 107.88 |
| SSD_PRSNT#12 | 235 | 205.7 | 114.24 |
| SSD_PRSNT#13 | 188.6 | 170.55 | 110.58 |
| SSD_PRSNT#14 | 243.68 | 155.69999999999999 | 156.5 |
| SSD_PRSNT#0_R | 2155.56 | 2125.39 | 101.42 |
| SSD_PRSNT#10_R | 1469.59 | 1692.39 | 86.84 |
| SSD_PRSNT#11_R | 6870.92 | 4545.82 | 151.15 |
| SSD_PRSNT#12_R | 1611.63 | 1705.86 | 94.48 |
| SSD_PRSNT#13_R | 7182.7 | 3663.45 | 196.06 |
| SSD_PRSNT#14_R | 1809.87 | 1937.25 | 93.42 |
| SSD_PRSNT#1_R | 3559.59 | 2323.06 | 153.22999999999999 |
| SSD_PRSNT#2_R | 2336.65 | 2473.3000000000002 | 94.48 |
| SSD_PRSNT#3_R | 1944.32 | 1822.87 | 106.66 |
| SSD_PRSNT#4_R | 3130.79 | 3457.09 | 90.56 |
| SSD_PRSNT#5_R | 2471 | 2174.4 | 113.64 |
| SSD_PRSNT#6_R | 719.79 | 698.93 | 102.98 |
| SSD_PRSNT#7_R | 3302.88 | 2499.4699999999998 | 132.13999999999999 |
| SSD_PRSNT#8_R | 5464.47 | 3259.52 | 167.65 |
| SSD_PRSNT#9_R | 2644.23 | 2436.73 | 108.52 |
| SSD_PWREN0 | 162.38 | 123.7 | 131.27000000000001 |
| SSD_PWREN1 | 242.4 | 123.7 | 195.96 |
| SSD_PWREN2 | 144.44999999999999 | 176.9 | 81.650000000000006 |
| SSD_PWREN3 | 132.78 | 124.44 | 106.7 |
| SSD_PWREN4 | 215.57 | 123.7 | 174.26 |
| SSD_PWREN5 | 144.44999999999999 | 176.9 | 81.650000000000006 |
| SSD_PWREN6 | 177.87 | 216.9 | 82.01 |
| SSD_PWREN7 | 138.5 | 155.26 | 89.2 |
| SSD_PWREN8 | 146.05000000000001 | 176.9 | 82.56 |
| SSD_PWREN9 | 150.43 | 176.9 | 85.04 |
| SSD_PWREN10 | 156.75 | 176.9 | 88.61 |
| SSD_PWREN11 | 114.94 | 115.26 | 99.72 |
| SSD_PWREN12 | 152.38 | 176.9 | 86.14 |
| SSD_PWREN13 | 112.45 | 113.76 | 98.85 |
| SSD_PWREN14 | 117.88 | 126.9 | 92.89 |
| SSD_PWREN0_R | 2413 | 2217.94 | 108.79 |
| SSD_PWREN10_R | 1734.24 | 1835.38 | 94.49 |
| SSD_PWREN11_R | 6653.02 | 4770.0600000000004 | 139.47 |
| SSD_PWREN12_R | 1477.14 | 1577.49 | 93.64 |
| SSD_PWREN13_R | 7522.07 | 3834.43 | 196.17 |
| SSD_PWREN14_R | 2068.2800000000002 | 1805.81 | 114.53 |
| SSD_PWREN1_R | 3720.04 | 3775.46 | 98.53 |
| SSD_PWREN2_R | 2365.23 | 2456.29 | 96.29 |
| SSD_PWREN3_R | 2014.68 | 1912.39 | 105.35 |
| SSD_PWREN4_R | 3251.65 | 3637.4 | 89.4 |
| SSD_PWREN5_R | 2634.23 | 2390.8200000000002 | 110.18 |
| SSD_PWREN6_R | 680.4 | 740.06 | 91.94 |
| SSD_PWREN7_R | 3365.85 | 2921.74 | 115.2 |
| SSD_PWREN8_R | 5308.47 | 3206.95 | 165.53 |
| SSD_PWREN9_R | 2651.49 | 2469.88 | 107.35 |
| TCA9554_INT_N | 9901.42 | 9875.5 | 100.26 |
| TCA9554_INT_N_R | 462.4 | 523.05999999999995 | 88.4 |
| TEMP_1_A0 | 315.75 | 380.94 | 82.89 |
| TEMP_1_A1 | 265.91000000000003 | 316.94 | 83.9 |
| TEMP_1_SCL | 136.6 | 83.46 | 163.66999999999999 |
| TEMP_1_SDA | 130.05000000000001 | 97.86 | 132.88999999999999 |
| TEMP_2_A0 | 190.12 | 158.80000000000001 | 119.72 |
| TEMP_2_A1 | 191.58 | 158.80000000000001 | 120.64 |
| TEMP_2_A2 | 198.76 | 173.2 | 114.76 |
| TEMP_2_ALERT | 138.16 | 121.3 | 113.9 |
| TEMP_2_SCL | 135.30000000000001 | 99.4 | 136.12 |
| TEMP_2_SDA | 132.21 | 98.2 | 134.63 |
| TEMP_3_A0 | 342.09 | 343.4 | 99.62 |
| TEMP_3_A1 | 253.13 | 227.8 | 111.12 |
| TEMP_3_A2 | 171.09 | 118.2 | 144.75 |
| TEMP_3_ALERT | 136.18 | 117.3 | 116.1 |
| TEMP_3_SCL | 142.99 | 99.4 | 143.85 |
| TEMP_3_SDA | 140.31 | 98.2 | 142.88 |
| TEMP_SENSOR_C | 8798.58 | 7199.56 | 122.21 |
| TEMP_SENSOR_DXN | 451.89 | 319.98 | 141.22999999999999 |
| TEMP_SENSOR_DXN_BJT | 9220.2000000000007 | 7282.44 | 126.61 |
| TEMP_SENSOR_DXP | 477.77 | 311.66000000000003 | 153.30000000000001 |
| TEMP_SENSOR_DXP_R | 8950.25 | 7192.4 | 124.44 |
| THERM_BASE | 1285.8 | 1231.56 | 104.4 |
| THERM_BASE_R | 156.83000000000001 | 179.63 | 87.31 |
| THERM_EMIT | 1265.49 | 1268.23 | 99.78 |
| THERM_EMIT_R | 75.87 | 81.28 | 93.35 |
| TPIN | 55.67 | 39.369999999999997 | 141.41 |
| TP_BMC0_LPC_LAD0 | 421.82 | 416.47 | 101.28 |
| TP_BMC0_LPC_LAD1 | 305.93 | 328.47 | 93.14 |
| TP_BMC0_LPC_LAD2 | 769.37 | 577.5 | 133.22 |
| TP_BMC0_LPC_LAD3 | 309.14999999999998 | 365.95 | 84.48 |
| TP_BMC_GPIOJ4 | 104.9 | 57.14 | 183.58 |
| TP_BMC_GPIOJ5 | 279.02999999999997 | 265.17 | 105.23 |
| TP_BMC_GPIOJ6 | 199.17 | 196.67 | 101.27 |
| TP_BMC_GPIOJ7 | 176.47 | 215.17 | 82.01 |
| TP_GPIOA3 | 330.49 | 369.06 | 89.55 |
| TP_GPIOA6 | 253.15 | 299.56 | 84.51 |
| TP_GPIOA7 | 323.23 | 356.07 | 90.78 |
| TP_GPIOB2 | 127.39 | 94.11 | 135.37 |
| TP_GPIOB5 | 170.84 | 160.93 | 106.16 |
| TP_GPIOB6 | 66.36 | 82.76 | 80.180000000000007 |
| TP_GPIOD0 | 183.02 | 234.96 | 77.89 |
| TP_GPIOD1 | 127.78 | 160.24 | 79.739999999999995 |
| TP_GPIOD2 | 278.51 | 349.95 | 79.58 |
| TP_GPIOD3 | 176.3 | 218.45 | 80.7 |
| TP_GPIOD4 | 139.62 | 183.94 | 75.900000000000006 |
| TP_GPIOD5 | 322.19 | 351.45 | 91.67 |
| TP_GPIOD7 | 564.61 | 629.04999999999995 | 89.76 |
| TP_GPIOE1 | 228.16 | 254.43 | 89.67 |
| TP_GPIOE2 | 200.51 | 229.24 | 87.47 |
| TP_GPIOE3 | 150.16 | 150.54 | 99.75 |
| TP_GPIOE6 | 223.65 | 230.93 | 96.85 |
| TP_GPIOE7 | 235.3 | 230.44 | 102.11 |
| TP_GPIOH3 | 191.26 | 254.57 | 75.13 |
| TP_GPIOH4 | 262.22000000000003 | 289.06 | 90.71 |
| TP_GPIOH5 | 273.98 | 320.85000000000002 | 85.39 |
| TP_GPIOH6 | 198.92 | 273.07 | 72.849999999999994 |
| TP_GPIOH7 | 348.18 | 350.56 | 99.32 |
| TP_GPIOI0 | 197.52 | 265.89999999999998 | 74.28 |
| TP_GPIOI1 | 62.65 | 30.36 | 206.35 |
| TP_GPIOI2 | 284.24 | 391.39 | 72.62 |
| TP_GPION5 | 158.16 | 108.67 | 145.54 |
| TP_GPIOO0 | 106.52 | 139.66 | 76.27 |
| TP_GPIOO1 | 94.38 | 90.17 | 104.66 |
| TP_GPIOO2 | 458.03 | 552.08000000000004 | 82.96 |
| TP_GPIOO4 | 125.02 | 158.16 | 79.040000000000006 |
| TP_GPIOO6 | 338.97 | 344.44 | 98.41 |
| TP_GPIOO7 | 60.17 | 19.309999999999999 | 311.58 |
| TP_GPIOP0 | 143.52000000000001 | 176.66 | 81.239999999999995 |
| TP_GPIOP1 | 306.27999999999997 | 307.18 | 99.71 |
| TP_GPIOP2 | 95.73 | 109.66 | 87.3 |
| TP_GPIOP4 | 258.64999999999998 | 268.67 | 96.27 |
| TP_GPIOP6 | 236.43 | 281.67 | 83.94 |
| TP_GPIOS4 | 436.43 | 410.03 | 106.44 |
| TP_GPIOT6 | 374.65 | 324.91000000000003 | 115.31 |
| TP_GPIOT7 | 578.08000000000004 | 416.58 | 138.77000000000001 |
| TP_GPIOU0 | 211.37 | 195.92 | 107.88 |
| TP_GPIOU1 | 188.9 | 180.42 | 104.7 |
| TP_GPIOU2 | 281.64999999999998 | 267.05 | 105.47 |
| TP_GPIOU3 | 258.18 | 248.55 | 103.87 |
| TP_GPIOV3 | 269.12 | 262.45999999999998 | 102.54 |
| TP_GPIOV4 | 157.46 | 171.56 | 91.78 |
| TP_GPIOV5 | 554.57000000000005 | 334.9 | 165.59 |
| TP_GPIOV6 | 263.14999999999998 | 260.55 | 101 |
| TP_GPIOV7 | 337.76 | 369.05 | 91.52 |
| TP_GPIOY3 | 266.77 | 325.43 | 81.97 |
| TP_IRQ_CPU_SERIAL | 453.65 | 611.94000000000005 | 74.13 |
| TP_LPC_CPU_CLKOUT0 | 308.56 | 382.96 | 80.569999999999993 |
| TP_LPC_CPU_FRAME_N | 230.52 | 279.97000000000003 | 82.34 |
| TP_RGMIICK | 327.27 | 357.98 | 91.42 |
| TP_SDP0 | 164.88 | 198.88 | 82.9 |
| TP_SDP2 | 140.86000000000001 | 146.56 | 96.11 |
| TP_SDP3 | 119.56 | 134.72999999999999 | 88.74 |
| TRAY_ID0 | 6675.48 | 6025.04 | 110.8 |
| TRAY_ID1 | 6876.95 | 6231.42 | 110.36 |
| TRAY_ID2 | 7075.48 | 6126.74 | 115.49 |
| TRAY_MBP_CTRL_EN_N | 7899.01 | 7682.99 | 102.81 |
| TRAY_POWER_CRIT_N | 6405.07 | 5891.42 | 108.72 |
| TRAY_RESET_N | 7027.54 | 6486.54 | 108.34 |
| TRAY_RESET_N_R | 161.88999999999999 | 64.88 | 249.52 |
| TWI_SCL0 | 11251.22 | 8199 | 137.22999999999999 |
| TWI_SCL1 | 25895.51 | 20592.45 | 125.75 |
| TWI_SCL2 | 2382.4499999999998 | 2107.1999999999998 | 113.06 |
| TWI_SCL3 | 5626.17 | 6314.27 | 89.1 |
| TWI_SCL4 | 634.95000000000005 | 617.51 | 102.82 |
| TWI_SCL5 | 474.4 | 439.29 | 107.99 |
| TWI_SCL6 | 55.66 | 0 | 1.#J |
| TWI_SCL10 | 443.23 | 418.36 | 105.95 |
| TWI_SCL2_R | 109.93 | 127.5 | 86.22 |
| TWI_SDA0 | 11279.86 | 8193 | 137.68 |
| TWI_SDA1 | 25571.21 | 20587.45 | 124.21 |
| TWI_SDA2 | 1941.26 | 1870.35 | 103.79 |
| TWI_SDA3 | 5480.3 | 6156.16 | 89.02 |
| TWI_SDA4 | 559.91 | 528.14 | 106.02 |
| TWI_SDA5 | 549.79 | 528.66 | 104 |
| TWI_SDA6 | 55.66 | 0 | 1.#J |
| TWI_SDA9 | 55.66 | 0 | 1.#J |
| TWI_SDA10 | 367.84 | 328.99 | 111.81 |
| TWI_SDA2_R | 105.78 | 117.5 | 90.03 |
| TWI_SRST#0 | 55.67 | 39.369999999999997 | 141.41 |
| TWI_SRST#1 | 55.66 | 0 | 1.#J |
| TWI_SRST#2 | 55.66 | 0 | 1.#J |
| TWI_SRST#3 | 55.67 | 39.369999999999997 | 141.41 |
| TWI_SRST#4 | 55.66 | 0 | 1.#J |
| TWI_SRST#5 | 95.03 | 39.369999999999997 | 241.39 |
| TWI_SRST#6 | 829.24 | 818.92 | 101.26 |
| TWI_SRST#7 | 95.04 | 78.739999999999995 | 120.71 |
| TWI_SRST#8 | 124.71 | 118.28 | 105.44 |
| TWI_SRST#9 | 55.67 | 39.369999999999997 | 141.41 |
| U19_PERST_N | 154.11000000000001 | 165.64 | 93.04 |
| U44_HOLD_N | 123.03 | 127.24 | 96.69 |
| U44_WP_N | 126.01 | 138.12 | 91.23 |
| U54_A0 | 200.41 | 203.1 | 98.67 |
| U54_A1 | 224.18 | 218.5 | 102.6 |
| U54_A2 | 276 | 274.89999999999998 | 100.4 |
| U54_INT_N | 176.32 | 221.3 | 79.680000000000007 |
| U54_P0 | 258.62 | 241.7 | 107 |
| U54_SCL | 148.24 | 124.23 | 119.33 |
| U54_SDA | 131.16 | 132.06 | 99.32 |
| U55_A0 | 155.58000000000001 | 103.52 | 150.29 |
| U55_A1 | 184.27 | 141.88 | 129.88 |
| U55_A2 | 164.45 | 126.48 | 130.02000000000001 |
| U55_INT_N | 155.33000000000001 | 128.07 | 121.28 |
| U55_P0 | 334.91 | 202.68 | 165.24 |
| U55_SCL | 149.66999999999999 | 136.46 | 109.68 |
| U55_SDA | 146.84 | 136.68 | 107.43 |
| U56_A0 | 153.34 | 144.28 | 106.28 |
| U56_A1 | 184.04 | 196.88 | 93.48 |
| U56_A2 | 171.17 | 181.48 | 94.32 |
| U56_INT_N | 158.32 | 152.32 | 103.94 |
| U56_SCL | 124.45 | 126.72 | 98.21 |
| U56_SDA | 125.97 | 142.12 | 88.63 |
| U80_B | 255.79 | 188 | 136.06 |
| U81_B | 357.99 | 253 | 141.5 |
| U81_Y | 220.74 | 166.4 | 132.66 |
| U82_MR# | 183.67 | 224 | 82 |
| U82_RST# | 114.05 | 93 | 122.63 |
| UART_COUNT | 12250.32 | 12878.39 | 95.12 |
| UART_SWITCH_R | 575.99 | 474.63 | 121.36 |
| UART_USIN | 9324.7000000000007 | 8075.47 | 115.47 |
| UART_USOUT | 9308.5 | 7952.1 | 117.06 |
| UPLINK1 | 12445.19 | 10108.549999999999 | 123.12 |
| UPLINK2 | 12279.52 | 10208.219999999999 | 120.29 |
| UPLINK3 | 11791.11 | 9751.35 | 120.92 |
| UPLINK4 | 11597.56 | 9688.7000000000007 | 119.7 |
| UPLINK5 | 3639.54 | 2356.37 | 154.46 |
| UPLINK6 | 3560.85 | 2382.5 | 149.46 |
| UPLINK7 | 3446.31 | 2606.1999999999998 | 132.24 |
| UPLINK8 | 3421.45 | 2620.9 | 130.54 |
| UPLINK1_R | 120.54 | 125.04 | 96.4 |
| UPLINK2_R | 253.56 | 155.01 | 163.58000000000001 |
| UPLINK3_R | 61.55 | 63.75 | 96.55 |
| UPLINK4_R | 112.18 | 144.86000000000001 | 77.44 |
| UPLINK5_R | 108.55 | 139.94 | 77.569999999999993 |
| UPLINK6_R | 104.17 | 92.15 | 113.04 |
| UPLINK7_R | 68.709999999999994 | 85.34 | 80.510000000000005 |
| UPLINK8_R | 121.29 | 109.67 | 110.59 |
| USB2_BMC_DN | 10276 | 8244.8799999999992 | 124.63 |
| USB2_BMC_DP | 10275.43 | 8244.98 | 124.63 |
| USB5V_EN | 199.6 | 238.15 | 83.81 |
| USB_DN_R | 559.01 | 494.06 | 113.15 |
| USB_DP_R | 559.30999999999995 | 572.16 | 97.75 |
| USB_OC# | 67.959999999999994 | 82.6 | 82.27 |
| USB_P1_F_DN1 | 580.76 | 580.83000000000004 | 99.99 |
| USB_P1_F_DP1 | 580.58000000000004 | 464.09 | 125.1 |
| USB_P2_DN | 4309.84 | 3083.24 | 139.78 |
| USB_P2_DP | 4309.0200000000004 | 3003.14 | 143.47999999999999 |
| USB_P4_DN_BMC | 14325.45 | 12957.46 | 110.56 |
| USB_P4_DP_BMC | 14325.37 | 12957.56 | 110.56 |
| V1PLLAV12 | 808.01 | 892.55 | 90.53 |
| VREF_2V2 | 145.86000000000001 | 139.11000000000001 | 104.85 |
| VR_P1V26_STBY_BIAS | 209.32 | 170.8 | 122.55 |
| VR_P1V26_STBY_EN_R | 173.88 | 103.8 | 167.51 |
| VR_P1V26_STBY_FB | 205.75 | 236.5 | 87 |
| VR_P1V26_STBY_IN | 0 | 244.3 | 0 |
| VR_P1V26_STBY_SS_C | 157.59 | 176.8 | 89.13 |
| VR_P1V538_STBY_BIAS | 237.57 | 230.8 | 102.93 |
| VR_P1V538_STBY_EN_R | 212.68 | 139.65 | 152.30000000000001 |
| VR_P1V538_STBY_FB | 172.46 | 191.5 | 90.06 |
| VR_P1V538_STBY_IN | 0 | 230.3 | 0 |
| VR_P1V538_STBY_SS_C | 141.41 | 136.80000000000001 | 103.37 |
| VR_P1V8_STBY_BIAS | 221.7 | 170.8 | 129.80000000000001 |
| VR_P1V8_STBY_EN_R | 178.96 | 103.8 | 172.41 |
| VR_P1V8_STBY_FB | 179.32 | 192.5 | 93.15 |
| VR_P1V8_STBY_IN | 398.16 | 269.3 | 147.85 |
| VR_P1V8_STBY_SS_C | 213.73 | 132.91 | 160.81 |
| VS1_LED | 10985.68 | 8200 | 133.97 |
| VS1_LED_R | 134.97999999999999 | 105.52 | 127.92 |
| VS2_LED | 11373.85 | 8020 | 141.82 |
| VS2_LED_R | 134.97999999999999 | 105.52 | 127.92 |
| VS3_LED | 11605.67 | 7864 | 147.58000000000001 |
| VS3_LED_R | 76.28 | 81.52 | 93.58 |
| VS4_LED | 2952.03 | 3285 | 89.86 |
| VS4_LED_R | 105.87 | 78.75 | 134.44 |
| VS5_LED | 2790.35 | 3110 | 89.72 |
| VS5_LED_R | 98.8 | 78.75 | 125.46 |
| VS6_LED | 2604.16 | 2925 | 89.03 |
| VS6_LED_R | 101.73 | 78.75 | 129.18 |
| VSS_571 | 408.73 | 388.93 | 105.09 |
| VSS_572 | 1038.5999999999999 | 961.59 | 108.01 |
| VSS_573 | 120.77 | 6.47 | 1866.63 |
| WP_DISABLE | 115.26 | 142.5 | 80.88 |
| WP_ENABLE | 133.76 | 181.5 | 73.7 |
| XTAL_IN_I210 | 154.29 | 186.06 | 82.93 |
| XTAL_IN_I210_R | 224.05 | 197.75 | 113.3 |
| XTAL_OUT_I210 | 131.4 | 164.75 | 79.75 |
| XTAL_OUT_I210_R | 193.93 | 209.75 | 92.46 |
| XTAL_X1 | 347.96 | 336.78 | 103.32 |
| XTAL_X2 | 114.12 | 133.77000000000001 | 85.31 |
| XTAL_X2_CLKGEN | 142.97 | 165.21 | 86.54 |
